FILE_TYPE = MACRO_DRAWING;
SET COLOR_WIRE YELLOW;
SET COLOR_PROP MONO;
SET COLOR_DOT WHITE;
SET COLOR_ARC YELLOW;
SET COLOR_BODY GREEN;
SET COLOR_NOTE MONO;
SET PROP_DISPLAY VALUE;
SET PAGE_NUMBER P60;
FORCEADD OFFPAGE..5
(-6425 525);
FORCEPROP 2 LAST $XR1 84 
J 0
(-6769 525);
DISPLAY 0.638298 (-6769 525);
PAINT MONO (-6769 525);
FORCEPROP 2 LAST $XR0 83 
J 0
(-6679 525);
DISPLAY 0.638298 (-6679 525);
PAINT MONO (-6679 525);
FORCEPROP 2 LAST CDS_LIB mstr_standard
J 0
(-6425 525);
PAINT MONO (-6425 525);
DISPLAY INVISIBLE (-6425 525);
FORCEPROP 1 LAST OFFPAGE TRUE
J 0
(-6100 400);
DISPLAY 1.170213 (-6100 400);
PAINT GREEN (-6100 400);
DISPLAY INVISIBLE (-6100 400);
FORCEPROP 1 LAST COMMENT_BODY TRUE
J 0
(-6325 450);
DISPLAY 1.170213 (-6325 450);
PAINT GREEN (-6325 450);
DISPLAY INVISIBLE (-6325 450);
FORCEPROP 2 LAST PATH I1
J 0
(-6375 600);
DISPLAY 1.021277 (-6375 600);
PAINT ORANGE (-6375 600);
DISPLAY INVISIBLE (-6375 600);
FORCEADD TAP..6
(-5575 825);
FORCEPROP 3 LASTPIN (-5525 825) SIG_NAME M_K_CLK_DP<0>
J 0
(-5515 835);
DISPLAY 0.659574 (-5515 835);
PAINT MONO (-5515 835);
DISPLAY INVISIBLE (-5515 835);
FORCEPROP 1 LASTPIN (-5525 825) BN 0
J 0
(-5577 833);
DISPLAY 0.617021 (-5577 833);
PAINT GREEN (-5577 833);
FORCEPROP 2 LAST CDS_LIB mstr_standard
J 0
(-5575 825);
PAINT MONO (-5575 825);
DISPLAY INVISIBLE (-5575 825);
FORCEPROP 1 LAST BODY_TYPE PLUMBING
J 0
(-5575 775);
DISPLAY 1.595745 (-5575 775);
PAINT GREEN (-5575 775);
DISPLAY INVISIBLE (-5575 775);
FORCEPROP 1 LAST HDL_TAP TRUE
J 0
(-5250 700);
DISPLAY 1.595745 (-5250 700);
PAINT GREEN (-5250 700);
DISPLAY INVISIBLE (-5250 700);
FORCEPROP 1 LAST PATH I10
J 0
(-5577 825);
DISPLAY 0.872340 (-5577 825);
PAINT GREEN (-5577 825);
DISPLAY INVISIBLE (-5577 825);
FORCEADD TAP..6
R 2
(-2850 1575);
FORCEPROP 3 LASTPIN (-2900 1575) SIG_NAME M_K_ODT<3>
J 0
(-2890 1585);
DISPLAY 0.659574 (-2890 1585);
PAINT MONO (-2890 1585);
DISPLAY INVISIBLE (-2890 1585);
FORCEPROP 1 LASTPIN (-2900 1575) BN 3
J 2
(-2848 1583);
DISPLAY 0.617021 (-2848 1583);
PAINT GREEN (-2848 1583);
FORCEPROP 2 LAST CDS_LIB mstr_standard
J 0
(-2850 1575);
PAINT MONO (-2850 1575);
DISPLAY INVISIBLE (-2850 1575);
FORCEPROP 1 LAST BODY_TYPE PLUMBING
J 2
(-2850 1525);
DISPLAY 1.595745 (-2850 1525);
PAINT GREEN (-2850 1525);
DISPLAY INVISIBLE (-2850 1525);
FORCEPROP 1 LAST HDL_TAP TRUE
J 2
(-3175 1450);
DISPLAY 1.595745 (-3175 1450);
PAINT GREEN (-3175 1450);
DISPLAY INVISIBLE (-3175 1450);
FORCEPROP 1 LAST PATH I100
J 2
(-2848 1575);
DISPLAY 0.872340 (-2848 1575);
PAINT GREEN (-2848 1575);
DISPLAY INVISIBLE (-2848 1575);
FORCEADD TAP..6
R 2
(-2850 1525);
FORCEPROP 3 LASTPIN (-2900 1525) SIG_NAME M_K_ODT<2>
J 0
(-2890 1535);
DISPLAY 0.659574 (-2890 1535);
PAINT MONO (-2890 1535);
DISPLAY INVISIBLE (-2890 1535);
FORCEPROP 1 LASTPIN (-2900 1525) BN 2
J 2
(-2848 1533);
DISPLAY 0.617021 (-2848 1533);
PAINT GREEN (-2848 1533);
FORCEPROP 2 LAST CDS_LIB mstr_standard
J 0
(-2850 1525);
PAINT MONO (-2850 1525);
DISPLAY INVISIBLE (-2850 1525);
FORCEPROP 1 LAST BODY_TYPE PLUMBING
J 2
(-2850 1475);
DISPLAY 1.595745 (-2850 1475);
PAINT GREEN (-2850 1475);
DISPLAY INVISIBLE (-2850 1475);
FORCEPROP 1 LAST HDL_TAP TRUE
J 2
(-3175 1400);
DISPLAY 1.595745 (-3175 1400);
PAINT GREEN (-3175 1400);
DISPLAY INVISIBLE (-3175 1400);
FORCEPROP 1 LAST PATH I101
J 2
(-2848 1525);
DISPLAY 0.872340 (-2848 1525);
PAINT GREEN (-2848 1525);
DISPLAY INVISIBLE (-2848 1525);
FORCEADD TAP..6
R 2
(-2850 1475);
FORCEPROP 3 LASTPIN (-2900 1475) SIG_NAME M_K_ODT<1>
J 0
(-2890 1485);
DISPLAY 0.659574 (-2890 1485);
PAINT MONO (-2890 1485);
DISPLAY INVISIBLE (-2890 1485);
FORCEPROP 1 LASTPIN (-2900 1475) BN 1
J 2
(-2848 1483);
DISPLAY 0.617021 (-2848 1483);
PAINT GREEN (-2848 1483);
FORCEPROP 2 LAST CDS_LIB mstr_standard
J 0
(-2850 1475);
PAINT MONO (-2850 1475);
DISPLAY INVISIBLE (-2850 1475);
FORCEPROP 1 LAST BODY_TYPE PLUMBING
J 2
(-2850 1425);
DISPLAY 1.595745 (-2850 1425);
PAINT GREEN (-2850 1425);
DISPLAY INVISIBLE (-2850 1425);
FORCEPROP 1 LAST HDL_TAP TRUE
J 2
(-3175 1350);
DISPLAY 1.595745 (-3175 1350);
PAINT GREEN (-3175 1350);
DISPLAY INVISIBLE (-3175 1350);
FORCEPROP 1 LAST PATH I102
J 2
(-2848 1475);
DISPLAY 0.872340 (-2848 1475);
PAINT GREEN (-2848 1475);
DISPLAY INVISIBLE (-2848 1475);
FORCEADD TAP..6
R 2
(-2850 1675);
FORCEPROP 3 LASTPIN (-2900 1675) SIG_NAME M_K_CKE<0>
J 0
(-2890 1685);
DISPLAY 0.659574 (-2890 1685);
PAINT MONO (-2890 1685);
DISPLAY INVISIBLE (-2890 1685);
FORCEPROP 1 LASTPIN (-2900 1675) BN 0
J 2
(-2848 1683);
DISPLAY 0.617021 (-2848 1683);
PAINT GREEN (-2848 1683);
FORCEPROP 2 LAST CDS_LIB mstr_standard
J 0
(-2850 1675);
PAINT MONO (-2850 1675);
DISPLAY INVISIBLE (-2850 1675);
FORCEPROP 1 LAST BODY_TYPE PLUMBING
J 2
(-2850 1625);
DISPLAY 1.595745 (-2850 1625);
PAINT GREEN (-2850 1625);
DISPLAY INVISIBLE (-2850 1625);
FORCEPROP 1 LAST HDL_TAP TRUE
J 2
(-3175 1550);
DISPLAY 1.595745 (-3175 1550);
PAINT GREEN (-3175 1550);
DISPLAY INVISIBLE (-3175 1550);
FORCEPROP 1 LAST PATH I103
J 2
(-2848 1675);
DISPLAY 0.872340 (-2848 1675);
PAINT GREEN (-2848 1675);
DISPLAY INVISIBLE (-2848 1675);
FORCEADD TAP..6
R 2
(-2850 1725);
FORCEPROP 3 LASTPIN (-2900 1725) SIG_NAME M_K_CKE<1>
J 0
(-2890 1735);
DISPLAY 0.659574 (-2890 1735);
PAINT MONO (-2890 1735);
DISPLAY INVISIBLE (-2890 1735);
FORCEPROP 1 LASTPIN (-2900 1725) BN 1
J 2
(-2848 1733);
DISPLAY 0.617021 (-2848 1733);
PAINT GREEN (-2848 1733);
FORCEPROP 2 LAST CDS_LIB mstr_standard
J 0
(-2850 1725);
PAINT MONO (-2850 1725);
DISPLAY INVISIBLE (-2850 1725);
FORCEPROP 1 LAST BODY_TYPE PLUMBING
J 2
(-2850 1675);
DISPLAY 1.595745 (-2850 1675);
PAINT GREEN (-2850 1675);
DISPLAY INVISIBLE (-2850 1675);
FORCEPROP 1 LAST HDL_TAP TRUE
J 2
(-3175 1600);
DISPLAY 1.595745 (-3175 1600);
PAINT GREEN (-3175 1600);
DISPLAY INVISIBLE (-3175 1600);
FORCEPROP 1 LAST PATH I104
J 2
(-2848 1725);
DISPLAY 0.872340 (-2848 1725);
PAINT GREEN (-2848 1725);
DISPLAY INVISIBLE (-2848 1725);
FORCEADD TAP..6
R 2
(-2850 1775);
FORCEPROP 3 LASTPIN (-2900 1775) SIG_NAME M_K_CKE<2>
J 0
(-2890 1785);
DISPLAY 0.659574 (-2890 1785);
PAINT MONO (-2890 1785);
DISPLAY INVISIBLE (-2890 1785);
FORCEPROP 1 LASTPIN (-2900 1775) BN 2
J 2
(-2848 1783);
DISPLAY 0.617021 (-2848 1783);
PAINT GREEN (-2848 1783);
FORCEPROP 2 LAST CDS_LIB mstr_standard
J 0
(-2850 1775);
PAINT MONO (-2850 1775);
DISPLAY INVISIBLE (-2850 1775);
FORCEPROP 1 LAST BODY_TYPE PLUMBING
J 2
(-2850 1725);
DISPLAY 1.595745 (-2850 1725);
PAINT GREEN (-2850 1725);
DISPLAY INVISIBLE (-2850 1725);
FORCEPROP 1 LAST HDL_TAP TRUE
J 2
(-3175 1650);
DISPLAY 1.595745 (-3175 1650);
PAINT GREEN (-3175 1650);
DISPLAY INVISIBLE (-3175 1650);
FORCEPROP 1 LAST PATH I105
J 2
(-2848 1775);
DISPLAY 0.872340 (-2848 1775);
PAINT GREEN (-2848 1775);
DISPLAY INVISIBLE (-2848 1775);
FORCEADD TAP..6
R 2
(-2850 1825);
FORCEPROP 3 LASTPIN (-2900 1825) SIG_NAME M_K_CKE<3>
J 0
(-2890 1835);
DISPLAY 0.659574 (-2890 1835);
PAINT MONO (-2890 1835);
DISPLAY INVISIBLE (-2890 1835);
FORCEPROP 1 LASTPIN (-2900 1825) BN 3
J 2
(-2848 1833);
DISPLAY 0.617021 (-2848 1833);
PAINT GREEN (-2848 1833);
FORCEPROP 2 LAST CDS_LIB mstr_standard
J 0
(-2850 1825);
PAINT MONO (-2850 1825);
DISPLAY INVISIBLE (-2850 1825);
FORCEPROP 1 LAST BODY_TYPE PLUMBING
J 2
(-2850 1775);
DISPLAY 1.595745 (-2850 1775);
PAINT GREEN (-2850 1775);
DISPLAY INVISIBLE (-2850 1775);
FORCEPROP 1 LAST HDL_TAP TRUE
J 2
(-3175 1700);
DISPLAY 1.595745 (-3175 1700);
PAINT GREEN (-3175 1700);
DISPLAY INVISIBLE (-3175 1700);
FORCEPROP 1 LAST PATH I106
J 2
(-2848 1825);
DISPLAY 0.872340 (-2848 1825);
PAINT GREEN (-2848 1825);
DISPLAY INVISIBLE (-2848 1825);
FORCEADD TAP..6
R 2
(-2850 1925);
FORCEPROP 3 LASTPIN (-2900 1925) SIG_NAME M_K_MA<0>
J 0
(-2890 1935);
DISPLAY 0.659574 (-2890 1935);
PAINT MONO (-2890 1935);
DISPLAY INVISIBLE (-2890 1935);
FORCEPROP 1 LASTPIN (-2900 1925) BN 0
J 2
(-2848 1933);
DISPLAY 0.617021 (-2848 1933);
PAINT GREEN (-2848 1933);
FORCEPROP 2 LAST CDS_LIB mstr_standard
J 0
(-2850 1925);
PAINT MONO (-2850 1925);
DISPLAY INVISIBLE (-2850 1925);
FORCEPROP 1 LAST BODY_TYPE PLUMBING
J 2
(-2850 1875);
DISPLAY 1.595745 (-2850 1875);
PAINT GREEN (-2850 1875);
DISPLAY INVISIBLE (-2850 1875);
FORCEPROP 1 LAST HDL_TAP TRUE
J 2
(-3175 1800);
DISPLAY 1.595745 (-3175 1800);
PAINT GREEN (-3175 1800);
DISPLAY INVISIBLE (-3175 1800);
FORCEPROP 1 LAST PATH I107
J 2
(-2848 1925);
DISPLAY 0.872340 (-2848 1925);
PAINT GREEN (-2848 1925);
DISPLAY INVISIBLE (-2848 1925);
FORCEADD TAP..6
R 2
(-2850 1975);
FORCEPROP 3 LASTPIN (-2900 1975) SIG_NAME M_K_MA<1>
J 0
(-2890 1985);
DISPLAY 0.659574 (-2890 1985);
PAINT MONO (-2890 1985);
DISPLAY INVISIBLE (-2890 1985);
FORCEPROP 1 LASTPIN (-2900 1975) BN 1
J 2
(-2848 1983);
DISPLAY 0.617021 (-2848 1983);
PAINT GREEN (-2848 1983);
FORCEPROP 2 LAST CDS_LIB mstr_standard
J 0
(-2850 1975);
PAINT MONO (-2850 1975);
DISPLAY INVISIBLE (-2850 1975);
FORCEPROP 1 LAST BODY_TYPE PLUMBING
J 2
(-2850 1925);
DISPLAY 1.595745 (-2850 1925);
PAINT GREEN (-2850 1925);
DISPLAY INVISIBLE (-2850 1925);
FORCEPROP 1 LAST HDL_TAP TRUE
J 2
(-3175 1850);
DISPLAY 1.595745 (-3175 1850);
PAINT GREEN (-3175 1850);
DISPLAY INVISIBLE (-3175 1850);
FORCEPROP 1 LAST PATH I108
J 2
(-2848 1975);
DISPLAY 0.872340 (-2848 1975);
PAINT GREEN (-2848 1975);
DISPLAY INVISIBLE (-2848 1975);
FORCEADD TAP..6
R 2
(-2850 2075);
FORCEPROP 3 LASTPIN (-2900 2075) SIG_NAME M_K_MA<3>
J 0
(-2890 2085);
DISPLAY 0.659574 (-2890 2085);
PAINT MONO (-2890 2085);
DISPLAY INVISIBLE (-2890 2085);
FORCEPROP 1 LASTPIN (-2900 2075) BN 3
J 2
(-2848 2083);
DISPLAY 0.617021 (-2848 2083);
PAINT GREEN (-2848 2083);
FORCEPROP 2 LAST CDS_LIB mstr_standard
J 0
(-2850 2075);
PAINT MONO (-2850 2075);
DISPLAY INVISIBLE (-2850 2075);
FORCEPROP 1 LAST BODY_TYPE PLUMBING
J 2
(-2850 2025);
DISPLAY 1.595745 (-2850 2025);
PAINT GREEN (-2850 2025);
DISPLAY INVISIBLE (-2850 2025);
FORCEPROP 1 LAST HDL_TAP TRUE
J 2
(-3175 1950);
DISPLAY 1.595745 (-3175 1950);
PAINT GREEN (-3175 1950);
DISPLAY INVISIBLE (-3175 1950);
FORCEPROP 1 LAST PATH I109
J 2
(-2848 2075);
DISPLAY 0.872340 (-2848 2075);
PAINT GREEN (-2848 2075);
DISPLAY INVISIBLE (-2848 2075);
FORCEADD TAP..6
(-5575 925);
FORCEPROP 3 LASTPIN (-5525 925) SIG_NAME M_K_CLK_DP<2>
J 0
(-5515 935);
DISPLAY 0.659574 (-5515 935);
PAINT MONO (-5515 935);
DISPLAY INVISIBLE (-5515 935);
FORCEPROP 1 LASTPIN (-5525 925) BN 2
J 0
(-5577 933);
DISPLAY 0.617021 (-5577 933);
PAINT GREEN (-5577 933);
FORCEPROP 2 LAST CDS_LIB mstr_standard
J 0
(-5575 925);
PAINT MONO (-5575 925);
DISPLAY INVISIBLE (-5575 925);
FORCEPROP 1 LAST BODY_TYPE PLUMBING
J 0
(-5575 875);
DISPLAY 1.595745 (-5575 875);
PAINT GREEN (-5575 875);
DISPLAY INVISIBLE (-5575 875);
FORCEPROP 1 LAST HDL_TAP TRUE
J 0
(-5250 800);
DISPLAY 1.595745 (-5250 800);
PAINT GREEN (-5250 800);
DISPLAY INVISIBLE (-5250 800);
FORCEPROP 1 LAST PATH I11
J 0
(-5577 925);
DISPLAY 0.872340 (-5577 925);
PAINT GREEN (-5577 925);
DISPLAY INVISIBLE (-5577 925);
FORCEADD TAP..6
R 2
(-2850 2025);
FORCEPROP 3 LASTPIN (-2900 2025) SIG_NAME M_K_MA<2>
J 0
(-2890 2035);
DISPLAY 0.659574 (-2890 2035);
PAINT MONO (-2890 2035);
DISPLAY INVISIBLE (-2890 2035);
FORCEPROP 1 LASTPIN (-2900 2025) BN 2
J 2
(-2848 2033);
DISPLAY 0.617021 (-2848 2033);
PAINT GREEN (-2848 2033);
FORCEPROP 2 LAST CDS_LIB mstr_standard
J 0
(-2850 2025);
PAINT MONO (-2850 2025);
DISPLAY INVISIBLE (-2850 2025);
FORCEPROP 1 LAST BODY_TYPE PLUMBING
J 2
(-2850 1975);
DISPLAY 1.595745 (-2850 1975);
PAINT GREEN (-2850 1975);
DISPLAY INVISIBLE (-2850 1975);
FORCEPROP 1 LAST HDL_TAP TRUE
J 2
(-3175 1900);
DISPLAY 1.595745 (-3175 1900);
PAINT GREEN (-3175 1900);
DISPLAY INVISIBLE (-3175 1900);
FORCEPROP 1 LAST PATH I110
J 2
(-2848 2025);
DISPLAY 0.872340 (-2848 2025);
PAINT GREEN (-2848 2025);
DISPLAY INVISIBLE (-2848 2025);
FORCEADD TAP..6
R 2
(-2850 2125);
FORCEPROP 3 LASTPIN (-2900 2125) SIG_NAME M_K_MA<4>
J 0
(-2890 2135);
DISPLAY 0.659574 (-2890 2135);
PAINT MONO (-2890 2135);
DISPLAY INVISIBLE (-2890 2135);
FORCEPROP 1 LASTPIN (-2900 2125) BN 4
J 2
(-2848 2133);
DISPLAY 0.617021 (-2848 2133);
PAINT GREEN (-2848 2133);
FORCEPROP 2 LAST CDS_LIB mstr_standard
J 0
(-2850 2125);
PAINT MONO (-2850 2125);
DISPLAY INVISIBLE (-2850 2125);
FORCEPROP 1 LAST BODY_TYPE PLUMBING
J 2
(-2850 2075);
DISPLAY 1.595745 (-2850 2075);
PAINT GREEN (-2850 2075);
DISPLAY INVISIBLE (-2850 2075);
FORCEPROP 1 LAST HDL_TAP TRUE
J 2
(-3175 2000);
DISPLAY 1.595745 (-3175 2000);
PAINT GREEN (-3175 2000);
DISPLAY INVISIBLE (-3175 2000);
FORCEPROP 1 LAST PATH I111
J 2
(-2848 2125);
DISPLAY 0.872340 (-2848 2125);
PAINT GREEN (-2848 2125);
DISPLAY INVISIBLE (-2848 2125);
FORCEADD TAP..6
R 2
(-2850 2175);
FORCEPROP 3 LASTPIN (-2900 2175) SIG_NAME M_K_MA<5>
J 0
(-2890 2185);
DISPLAY 0.659574 (-2890 2185);
PAINT MONO (-2890 2185);
DISPLAY INVISIBLE (-2890 2185);
FORCEPROP 1 LASTPIN (-2900 2175) BN 5
J 2
(-2848 2183);
DISPLAY 0.617021 (-2848 2183);
PAINT GREEN (-2848 2183);
FORCEPROP 2 LAST CDS_LIB mstr_standard
J 0
(-2850 2175);
PAINT MONO (-2850 2175);
DISPLAY INVISIBLE (-2850 2175);
FORCEPROP 1 LAST BODY_TYPE PLUMBING
J 2
(-2850 2125);
DISPLAY 1.595745 (-2850 2125);
PAINT GREEN (-2850 2125);
DISPLAY INVISIBLE (-2850 2125);
FORCEPROP 1 LAST HDL_TAP TRUE
J 2
(-3175 2050);
DISPLAY 1.595745 (-3175 2050);
PAINT GREEN (-3175 2050);
DISPLAY INVISIBLE (-3175 2050);
FORCEPROP 1 LAST PATH I112
J 2
(-2848 2175);
DISPLAY 0.872340 (-2848 2175);
PAINT GREEN (-2848 2175);
DISPLAY INVISIBLE (-2848 2175);
FORCEADD TAP..6
R 2
(-2850 2225);
FORCEPROP 3 LASTPIN (-2900 2225) SIG_NAME M_K_MA<6>
J 0
(-2890 2235);
DISPLAY 0.659574 (-2890 2235);
PAINT MONO (-2890 2235);
DISPLAY INVISIBLE (-2890 2235);
FORCEPROP 1 LASTPIN (-2900 2225) BN 6
J 2
(-2848 2233);
DISPLAY 0.617021 (-2848 2233);
PAINT GREEN (-2848 2233);
FORCEPROP 2 LAST CDS_LIB mstr_standard
J 0
(-2850 2225);
PAINT MONO (-2850 2225);
DISPLAY INVISIBLE (-2850 2225);
FORCEPROP 1 LAST BODY_TYPE PLUMBING
J 2
(-2850 2175);
DISPLAY 1.595745 (-2850 2175);
PAINT GREEN (-2850 2175);
DISPLAY INVISIBLE (-2850 2175);
FORCEPROP 1 LAST HDL_TAP TRUE
J 2
(-3175 2100);
DISPLAY 1.595745 (-3175 2100);
PAINT GREEN (-3175 2100);
DISPLAY INVISIBLE (-3175 2100);
FORCEPROP 1 LAST PATH I113
J 2
(-2848 2225);
DISPLAY 0.872340 (-2848 2225);
PAINT GREEN (-2848 2225);
DISPLAY INVISIBLE (-2848 2225);
FORCEADD TAP..6
R 2
(-2850 2325);
FORCEPROP 3 LASTPIN (-2900 2325) SIG_NAME M_K_MA<8>
J 0
(-2890 2335);
DISPLAY 0.659574 (-2890 2335);
PAINT MONO (-2890 2335);
DISPLAY INVISIBLE (-2890 2335);
FORCEPROP 1 LASTPIN (-2900 2325) BN 8
J 2
(-2848 2333);
DISPLAY 0.617021 (-2848 2333);
PAINT GREEN (-2848 2333);
FORCEPROP 2 LAST CDS_LIB mstr_standard
J 0
(-2850 2325);
PAINT MONO (-2850 2325);
DISPLAY INVISIBLE (-2850 2325);
FORCEPROP 1 LAST BODY_TYPE PLUMBING
J 2
(-2850 2275);
DISPLAY 1.595745 (-2850 2275);
PAINT GREEN (-2850 2275);
DISPLAY INVISIBLE (-2850 2275);
FORCEPROP 1 LAST HDL_TAP TRUE
J 2
(-3175 2200);
DISPLAY 1.595745 (-3175 2200);
PAINT GREEN (-3175 2200);
DISPLAY INVISIBLE (-3175 2200);
FORCEPROP 1 LAST PATH I114
J 2
(-2848 2325);
DISPLAY 0.872340 (-2848 2325);
PAINT GREEN (-2848 2325);
DISPLAY INVISIBLE (-2848 2325);
FORCEADD TAP..6
R 2
(-2850 2275);
FORCEPROP 3 LASTPIN (-2900 2275) SIG_NAME M_K_MA<7>
J 0
(-2890 2285);
DISPLAY 0.659574 (-2890 2285);
PAINT MONO (-2890 2285);
DISPLAY INVISIBLE (-2890 2285);
FORCEPROP 1 LASTPIN (-2900 2275) BN 7
J 2
(-2848 2283);
DISPLAY 0.617021 (-2848 2283);
PAINT GREEN (-2848 2283);
FORCEPROP 2 LAST CDS_LIB mstr_standard
J 0
(-2850 2275);
PAINT MONO (-2850 2275);
DISPLAY INVISIBLE (-2850 2275);
FORCEPROP 1 LAST BODY_TYPE PLUMBING
J 2
(-2850 2225);
DISPLAY 1.595745 (-2850 2225);
PAINT GREEN (-2850 2225);
DISPLAY INVISIBLE (-2850 2225);
FORCEPROP 1 LAST HDL_TAP TRUE
J 2
(-3175 2150);
DISPLAY 1.595745 (-3175 2150);
PAINT GREEN (-3175 2150);
DISPLAY INVISIBLE (-3175 2150);
FORCEPROP 1 LAST PATH I115
J 2
(-2848 2275);
DISPLAY 0.872340 (-2848 2275);
PAINT GREEN (-2848 2275);
DISPLAY INVISIBLE (-2848 2275);
FORCEADD TAP..6
R 2
(-2850 2475);
FORCEPROP 3 LASTPIN (-2900 2475) SIG_NAME M_K_MA<11>
J 0
(-2890 2485);
DISPLAY 0.659574 (-2890 2485);
PAINT MONO (-2890 2485);
DISPLAY INVISIBLE (-2890 2485);
FORCEPROP 1 LASTPIN (-2900 2475) BN 11
J 2
(-2848 2483);
DISPLAY 0.617021 (-2848 2483);
PAINT GREEN (-2848 2483);
FORCEPROP 2 LAST CDS_LIB mstr_standard
J 0
(-2850 2475);
PAINT MONO (-2850 2475);
DISPLAY INVISIBLE (-2850 2475);
FORCEPROP 1 LAST BODY_TYPE PLUMBING
J 2
(-2850 2425);
DISPLAY 1.595745 (-2850 2425);
PAINT GREEN (-2850 2425);
DISPLAY INVISIBLE (-2850 2425);
FORCEPROP 1 LAST HDL_TAP TRUE
J 2
(-3175 2350);
DISPLAY 1.595745 (-3175 2350);
PAINT GREEN (-3175 2350);
DISPLAY INVISIBLE (-3175 2350);
FORCEPROP 1 LAST PATH I116
J 2
(-2848 2475);
DISPLAY 0.872340 (-2848 2475);
PAINT GREEN (-2848 2475);
DISPLAY INVISIBLE (-2848 2475);
FORCEADD TAP..6
R 2
(-2850 2425);
FORCEPROP 3 LASTPIN (-2900 2425) SIG_NAME M_K_MA<10>
J 0
(-2890 2435);
DISPLAY 0.659574 (-2890 2435);
PAINT MONO (-2890 2435);
DISPLAY INVISIBLE (-2890 2435);
FORCEPROP 1 LASTPIN (-2900 2425) BN 10
J 2
(-2848 2433);
DISPLAY 0.617021 (-2848 2433);
PAINT GREEN (-2848 2433);
FORCEPROP 2 LAST CDS_LIB mstr_standard
J 0
(-2850 2425);
PAINT MONO (-2850 2425);
DISPLAY INVISIBLE (-2850 2425);
FORCEPROP 1 LAST BODY_TYPE PLUMBING
J 2
(-2850 2375);
DISPLAY 1.595745 (-2850 2375);
PAINT GREEN (-2850 2375);
DISPLAY INVISIBLE (-2850 2375);
FORCEPROP 1 LAST HDL_TAP TRUE
J 2
(-3175 2300);
DISPLAY 1.595745 (-3175 2300);
PAINT GREEN (-3175 2300);
DISPLAY INVISIBLE (-3175 2300);
FORCEPROP 1 LAST PATH I117
J 2
(-2848 2425);
DISPLAY 0.872340 (-2848 2425);
PAINT GREEN (-2848 2425);
DISPLAY INVISIBLE (-2848 2425);
FORCEADD TAP..6
R 2
(-2850 2375);
FORCEPROP 3 LASTPIN (-2900 2375) SIG_NAME M_K_MA<9>
J 0
(-2890 2385);
DISPLAY 0.659574 (-2890 2385);
PAINT MONO (-2890 2385);
DISPLAY INVISIBLE (-2890 2385);
FORCEPROP 1 LASTPIN (-2900 2375) BN 9
J 2
(-2848 2383);
DISPLAY 0.617021 (-2848 2383);
PAINT GREEN (-2848 2383);
FORCEPROP 2 LAST CDS_LIB mstr_standard
J 0
(-2850 2375);
PAINT MONO (-2850 2375);
DISPLAY INVISIBLE (-2850 2375);
FORCEPROP 1 LAST BODY_TYPE PLUMBING
J 2
(-2850 2325);
DISPLAY 1.595745 (-2850 2325);
PAINT GREEN (-2850 2325);
DISPLAY INVISIBLE (-2850 2325);
FORCEPROP 1 LAST HDL_TAP TRUE
J 2
(-3175 2250);
DISPLAY 1.595745 (-3175 2250);
PAINT GREEN (-3175 2250);
DISPLAY INVISIBLE (-3175 2250);
FORCEPROP 1 LAST PATH I118
J 2
(-2848 2375);
DISPLAY 0.872340 (-2848 2375);
PAINT GREEN (-2848 2375);
DISPLAY INVISIBLE (-2848 2375);
FORCEADD TAP..6
R 2
(-2850 2525);
FORCEPROP 3 LASTPIN (-2900 2525) SIG_NAME M_K_MA<12>
J 0
(-2890 2535);
DISPLAY 0.659574 (-2890 2535);
PAINT MONO (-2890 2535);
DISPLAY INVISIBLE (-2890 2535);
FORCEPROP 1 LASTPIN (-2900 2525) BN 12
J 2
(-2848 2533);
DISPLAY 0.617021 (-2848 2533);
PAINT GREEN (-2848 2533);
FORCEPROP 2 LAST CDS_LIB mstr_standard
J 0
(-2850 2525);
PAINT MONO (-2850 2525);
DISPLAY INVISIBLE (-2850 2525);
FORCEPROP 1 LAST BODY_TYPE PLUMBING
J 2
(-2850 2475);
DISPLAY 1.595745 (-2850 2475);
PAINT GREEN (-2850 2475);
DISPLAY INVISIBLE (-2850 2475);
FORCEPROP 1 LAST HDL_TAP TRUE
J 2
(-3175 2400);
DISPLAY 1.595745 (-3175 2400);
PAINT GREEN (-3175 2400);
DISPLAY INVISIBLE (-3175 2400);
FORCEPROP 1 LAST PATH I119
J 2
(-2848 2525);
DISPLAY 0.872340 (-2848 2525);
PAINT GREEN (-2848 2525);
DISPLAY INVISIBLE (-2848 2525);
FORCEADD TAP..6
(-5575 975);
FORCEPROP 3 LASTPIN (-5525 975) SIG_NAME M_K_CLK_DP<3>
J 0
(-5515 985);
DISPLAY 0.659574 (-5515 985);
PAINT MONO (-5515 985);
DISPLAY INVISIBLE (-5515 985);
FORCEPROP 1 LASTPIN (-5525 975) BN 3
J 0
(-5577 983);
DISPLAY 0.617021 (-5577 983);
PAINT GREEN (-5577 983);
FORCEPROP 2 LAST CDS_LIB mstr_standard
J 0
(-5575 975);
PAINT MONO (-5575 975);
DISPLAY INVISIBLE (-5575 975);
FORCEPROP 1 LAST BODY_TYPE PLUMBING
J 0
(-5575 925);
DISPLAY 1.595745 (-5575 925);
PAINT GREEN (-5575 925);
DISPLAY INVISIBLE (-5575 925);
FORCEPROP 1 LAST HDL_TAP TRUE
J 0
(-5250 850);
DISPLAY 1.595745 (-5250 850);
PAINT GREEN (-5250 850);
DISPLAY INVISIBLE (-5250 850);
FORCEPROP 1 LAST PATH I12
J 0
(-5577 975);
DISPLAY 0.872340 (-5577 975);
PAINT GREEN (-5577 975);
DISPLAY INVISIBLE (-5577 975);
FORCEADD TAP..6
R 2
(-2850 2575);
FORCEPROP 3 LASTPIN (-2900 2575) SIG_NAME M_K_MA<13>
J 0
(-2890 2585);
DISPLAY 0.659574 (-2890 2585);
PAINT MONO (-2890 2585);
DISPLAY INVISIBLE (-2890 2585);
FORCEPROP 1 LASTPIN (-2900 2575) BN 13
J 2
(-2848 2583);
DISPLAY 0.617021 (-2848 2583);
PAINT GREEN (-2848 2583);
FORCEPROP 2 LAST CDS_LIB mstr_standard
J 0
(-2850 2575);
PAINT MONO (-2850 2575);
DISPLAY INVISIBLE (-2850 2575);
FORCEPROP 1 LAST BODY_TYPE PLUMBING
J 2
(-2850 2525);
DISPLAY 1.595745 (-2850 2525);
PAINT GREEN (-2850 2525);
DISPLAY INVISIBLE (-2850 2525);
FORCEPROP 1 LAST HDL_TAP TRUE
J 2
(-3175 2450);
DISPLAY 1.595745 (-3175 2450);
PAINT GREEN (-3175 2450);
DISPLAY INVISIBLE (-3175 2450);
FORCEPROP 1 LAST PATH I120
J 2
(-2848 2575);
DISPLAY 0.872340 (-2848 2575);
PAINT GREEN (-2848 2575);
DISPLAY INVISIBLE (-2848 2575);
FORCEADD TAP..6
R 2
(-2850 2625);
FORCEPROP 3 LASTPIN (-2900 2625) SIG_NAME M_K_MA<14>
J 0
(-2890 2635);
DISPLAY 0.659574 (-2890 2635);
PAINT MONO (-2890 2635);
DISPLAY INVISIBLE (-2890 2635);
FORCEPROP 1 LASTPIN (-2900 2625) BN 14
J 2
(-2848 2633);
DISPLAY 0.617021 (-2848 2633);
PAINT GREEN (-2848 2633);
FORCEPROP 2 LAST CDS_LIB mstr_standard
J 0
(-2850 2625);
PAINT MONO (-2850 2625);
DISPLAY INVISIBLE (-2850 2625);
FORCEPROP 1 LAST BODY_TYPE PLUMBING
J 2
(-2850 2575);
DISPLAY 1.595745 (-2850 2575);
PAINT GREEN (-2850 2575);
DISPLAY INVISIBLE (-2850 2575);
FORCEPROP 1 LAST HDL_TAP TRUE
J 2
(-3175 2500);
DISPLAY 1.595745 (-3175 2500);
PAINT GREEN (-3175 2500);
DISPLAY INVISIBLE (-3175 2500);
FORCEPROP 1 LAST PATH I121
J 2
(-2848 2625);
DISPLAY 0.872340 (-2848 2625);
PAINT GREEN (-2848 2625);
DISPLAY INVISIBLE (-2848 2625);
FORCEADD TAP..6
R 2
(-2850 2675);
FORCEPROP 3 LASTPIN (-2900 2675) SIG_NAME M_K_MA<15>
J 0
(-2890 2685);
DISPLAY 0.659574 (-2890 2685);
PAINT MONO (-2890 2685);
DISPLAY INVISIBLE (-2890 2685);
FORCEPROP 1 LASTPIN (-2900 2675) BN 15
J 2
(-2848 2683);
DISPLAY 0.617021 (-2848 2683);
PAINT GREEN (-2848 2683);
FORCEPROP 2 LAST CDS_LIB mstr_standard
J 0
(-2850 2675);
PAINT MONO (-2850 2675);
DISPLAY INVISIBLE (-2850 2675);
FORCEPROP 1 LAST BODY_TYPE PLUMBING
J 2
(-2850 2625);
DISPLAY 1.595745 (-2850 2625);
PAINT GREEN (-2850 2625);
DISPLAY INVISIBLE (-2850 2625);
FORCEPROP 1 LAST HDL_TAP TRUE
J 2
(-3175 2550);
DISPLAY 1.595745 (-3175 2550);
PAINT GREEN (-3175 2550);
DISPLAY INVISIBLE (-3175 2550);
FORCEPROP 1 LAST PATH I122
J 2
(-2848 2675);
DISPLAY 0.872340 (-2848 2675);
PAINT GREEN (-2848 2675);
DISPLAY INVISIBLE (-2848 2675);
FORCEADD TAP..6
R 2
(-2850 2725);
FORCEPROP 3 LASTPIN (-2900 2725) SIG_NAME M_K_MA<16>
J 0
(-2890 2735);
DISPLAY 0.659574 (-2890 2735);
PAINT MONO (-2890 2735);
DISPLAY INVISIBLE (-2890 2735);
FORCEPROP 1 LASTPIN (-2900 2725) BN 16
J 2
(-2848 2733);
DISPLAY 0.617021 (-2848 2733);
PAINT GREEN (-2848 2733);
FORCEPROP 2 LAST CDS_LIB mstr_standard
J 0
(-2850 2725);
PAINT MONO (-2850 2725);
DISPLAY INVISIBLE (-2850 2725);
FORCEPROP 1 LAST BODY_TYPE PLUMBING
J 2
(-2850 2675);
DISPLAY 1.595745 (-2850 2675);
PAINT GREEN (-2850 2675);
DISPLAY INVISIBLE (-2850 2675);
FORCEPROP 1 LAST HDL_TAP TRUE
J 2
(-3175 2600);
DISPLAY 1.595745 (-3175 2600);
PAINT GREEN (-3175 2600);
DISPLAY INVISIBLE (-3175 2600);
FORCEPROP 1 LAST PATH I123
J 2
(-2848 2725);
DISPLAY 0.872340 (-2848 2725);
PAINT GREEN (-2848 2725);
DISPLAY INVISIBLE (-2848 2725);
FORCEADD TAP..6
R 2
(-2850 2775);
FORCEPROP 3 LASTPIN (-2900 2775) SIG_NAME M_K_MA<17>
J 0
(-2890 2785);
DISPLAY 0.659574 (-2890 2785);
PAINT MONO (-2890 2785);
DISPLAY INVISIBLE (-2890 2785);
FORCEPROP 1 LASTPIN (-2900 2775) BN 17
J 2
(-2848 2783);
DISPLAY 0.617021 (-2848 2783);
PAINT GREEN (-2848 2783);
FORCEPROP 2 LAST CDS_LIB mstr_standard
J 0
(-2850 2775);
PAINT MONO (-2850 2775);
DISPLAY INVISIBLE (-2850 2775);
FORCEPROP 1 LAST BODY_TYPE PLUMBING
J 2
(-2850 2725);
DISPLAY 1.595745 (-2850 2725);
PAINT GREEN (-2850 2725);
DISPLAY INVISIBLE (-2850 2725);
FORCEPROP 1 LAST HDL_TAP TRUE
J 2
(-3175 2650);
DISPLAY 1.595745 (-3175 2650);
PAINT GREEN (-3175 2650);
DISPLAY INVISIBLE (-3175 2650);
FORCEPROP 1 LAST PATH I124
J 2
(-2848 2775);
DISPLAY 0.872340 (-2848 2775);
PAINT GREEN (-2848 2775);
DISPLAY INVISIBLE (-2848 2775);
FORCEADD TAP..6
R 2
(-2850 2925);
FORCEPROP 3 LASTPIN (-2900 2925) SIG_NAME M_K_DQS_DN<1>
J 0
(-2890 2935);
DISPLAY 0.659574 (-2890 2935);
PAINT MONO (-2890 2935);
DISPLAY INVISIBLE (-2890 2935);
FORCEPROP 1 LASTPIN (-2900 2925) BN 1
J 2
(-2848 2933);
DISPLAY 0.617021 (-2848 2933);
PAINT GREEN (-2848 2933);
FORCEPROP 2 LAST CDS_LIB mstr_standard
J 0
(-2850 2925);
PAINT MONO (-2850 2925);
DISPLAY INVISIBLE (-2850 2925);
FORCEPROP 1 LAST BODY_TYPE PLUMBING
J 2
(-2850 2875);
DISPLAY 1.595745 (-2850 2875);
PAINT GREEN (-2850 2875);
DISPLAY INVISIBLE (-2850 2875);
FORCEPROP 1 LAST HDL_TAP TRUE
J 2
(-3175 2800);
DISPLAY 1.595745 (-3175 2800);
PAINT GREEN (-3175 2800);
DISPLAY INVISIBLE (-3175 2800);
FORCEPROP 1 LAST PATH I125
J 2
(-2848 2925);
DISPLAY 0.872340 (-2848 2925);
PAINT GREEN (-2848 2925);
DISPLAY INVISIBLE (-2848 2925);
FORCEADD TAP..6
R 2
(-2850 2975);
FORCEPROP 3 LASTPIN (-2900 2975) SIG_NAME M_K_DQS_DN<2>
J 0
(-2890 2985);
DISPLAY 0.659574 (-2890 2985);
PAINT MONO (-2890 2985);
DISPLAY INVISIBLE (-2890 2985);
FORCEPROP 1 LASTPIN (-2900 2975) BN 2
J 2
(-2848 2983);
DISPLAY 0.617021 (-2848 2983);
PAINT GREEN (-2848 2983);
FORCEPROP 2 LAST CDS_LIB mstr_standard
J 0
(-2850 2975);
PAINT MONO (-2850 2975);
DISPLAY INVISIBLE (-2850 2975);
FORCEPROP 1 LAST BODY_TYPE PLUMBING
J 2
(-2850 2925);
DISPLAY 1.595745 (-2850 2925);
PAINT GREEN (-2850 2925);
DISPLAY INVISIBLE (-2850 2925);
FORCEPROP 1 LAST HDL_TAP TRUE
J 2
(-3175 2850);
DISPLAY 1.595745 (-3175 2850);
PAINT GREEN (-3175 2850);
DISPLAY INVISIBLE (-3175 2850);
FORCEPROP 1 LAST PATH I126
J 2
(-2848 2975);
DISPLAY 0.872340 (-2848 2975);
PAINT GREEN (-2848 2975);
DISPLAY INVISIBLE (-2848 2975);
FORCEADD TAP..6
R 2
(-2850 2875);
FORCEPROP 3 LASTPIN (-2900 2875) SIG_NAME M_K_DQS_DN<0>
J 0
(-2890 2885);
DISPLAY 0.659574 (-2890 2885);
PAINT MONO (-2890 2885);
DISPLAY INVISIBLE (-2890 2885);
FORCEPROP 1 LASTPIN (-2900 2875) BN 0
J 2
(-2848 2883);
DISPLAY 0.617021 (-2848 2883);
PAINT GREEN (-2848 2883);
FORCEPROP 2 LAST CDS_LIB mstr_standard
J 0
(-2850 2875);
PAINT MONO (-2850 2875);
DISPLAY INVISIBLE (-2850 2875);
FORCEPROP 1 LAST BODY_TYPE PLUMBING
J 2
(-2850 2825);
DISPLAY 1.595745 (-2850 2825);
PAINT GREEN (-2850 2825);
DISPLAY INVISIBLE (-2850 2825);
FORCEPROP 1 LAST HDL_TAP TRUE
J 2
(-3175 2750);
DISPLAY 1.595745 (-3175 2750);
PAINT GREEN (-3175 2750);
DISPLAY INVISIBLE (-3175 2750);
FORCEPROP 1 LAST PATH I127
J 2
(-2848 2875);
DISPLAY 0.872340 (-2848 2875);
PAINT GREEN (-2848 2875);
DISPLAY INVISIBLE (-2848 2875);
FORCEADD TAP..6
R 2
(-2850 3075);
FORCEPROP 3 LASTPIN (-2900 3075) SIG_NAME M_K_DQS_DN<4>
J 0
(-2890 3085);
DISPLAY 0.659574 (-2890 3085);
PAINT MONO (-2890 3085);
DISPLAY INVISIBLE (-2890 3085);
FORCEPROP 1 LASTPIN (-2900 3075) BN 4
J 2
(-2848 3083);
DISPLAY 0.617021 (-2848 3083);
PAINT GREEN (-2848 3083);
FORCEPROP 2 LAST CDS_LIB mstr_standard
J 0
(-2850 3075);
PAINT MONO (-2850 3075);
DISPLAY INVISIBLE (-2850 3075);
FORCEPROP 1 LAST BODY_TYPE PLUMBING
J 2
(-2850 3025);
DISPLAY 1.595745 (-2850 3025);
PAINT GREEN (-2850 3025);
DISPLAY INVISIBLE (-2850 3025);
FORCEPROP 1 LAST HDL_TAP TRUE
J 2
(-3175 2950);
DISPLAY 1.595745 (-3175 2950);
PAINT GREEN (-3175 2950);
DISPLAY INVISIBLE (-3175 2950);
FORCEPROP 1 LAST PATH I128
J 2
(-2848 3075);
DISPLAY 0.872340 (-2848 3075);
PAINT GREEN (-2848 3075);
DISPLAY INVISIBLE (-2848 3075);
FORCEADD TAP..6
R 2
(-2850 3025);
FORCEPROP 3 LASTPIN (-2900 3025) SIG_NAME M_K_DQS_DN<3>
J 0
(-2890 3035);
DISPLAY 0.659574 (-2890 3035);
PAINT MONO (-2890 3035);
DISPLAY INVISIBLE (-2890 3035);
FORCEPROP 1 LASTPIN (-2900 3025) BN 3
J 2
(-2848 3033);
DISPLAY 0.617021 (-2848 3033);
PAINT GREEN (-2848 3033);
FORCEPROP 2 LAST CDS_LIB mstr_standard
J 0
(-2850 3025);
PAINT MONO (-2850 3025);
DISPLAY INVISIBLE (-2850 3025);
FORCEPROP 1 LAST BODY_TYPE PLUMBING
J 2
(-2850 2975);
DISPLAY 1.595745 (-2850 2975);
PAINT GREEN (-2850 2975);
DISPLAY INVISIBLE (-2850 2975);
FORCEPROP 1 LAST HDL_TAP TRUE
J 2
(-3175 2900);
DISPLAY 1.595745 (-3175 2900);
PAINT GREEN (-3175 2900);
DISPLAY INVISIBLE (-3175 2900);
FORCEPROP 1 LAST PATH I129
J 2
(-2848 3025);
DISPLAY 0.872340 (-2848 3025);
PAINT GREEN (-2848 3025);
DISPLAY INVISIBLE (-2848 3025);
FORCEADD TAP..6
(-5575 1075);
FORCEPROP 3 LASTPIN (-5525 1075) SIG_NAME M_K_ECC<0>
J 0
(-5515 1085);
DISPLAY 0.659574 (-5515 1085);
PAINT MONO (-5515 1085);
DISPLAY INVISIBLE (-5515 1085);
FORCEPROP 1 LASTPIN (-5525 1075) BN 0
J 0
(-5577 1083);
DISPLAY 0.617021 (-5577 1083);
PAINT GREEN (-5577 1083);
FORCEPROP 2 LAST CDS_LIB mstr_standard
J 0
(-5575 1075);
PAINT MONO (-5575 1075);
DISPLAY INVISIBLE (-5575 1075);
FORCEPROP 1 LAST BODY_TYPE PLUMBING
J 0
(-5575 1025);
DISPLAY 1.595745 (-5575 1025);
PAINT GREEN (-5575 1025);
DISPLAY INVISIBLE (-5575 1025);
FORCEPROP 1 LAST HDL_TAP TRUE
J 0
(-5250 950);
DISPLAY 1.595745 (-5250 950);
PAINT GREEN (-5250 950);
DISPLAY INVISIBLE (-5250 950);
FORCEPROP 1 LAST PATH I13
J 0
(-5577 1075);
DISPLAY 0.872340 (-5577 1075);
PAINT GREEN (-5577 1075);
DISPLAY INVISIBLE (-5577 1075);
FORCEADD TAP..6
R 2
(-2850 3125);
FORCEPROP 3 LASTPIN (-2900 3125) SIG_NAME M_K_DQS_DN<5>
J 0
(-2890 3135);
DISPLAY 0.659574 (-2890 3135);
PAINT MONO (-2890 3135);
DISPLAY INVISIBLE (-2890 3135);
FORCEPROP 1 LASTPIN (-2900 3125) BN 5
J 2
(-2848 3133);
DISPLAY 0.617021 (-2848 3133);
PAINT GREEN (-2848 3133);
FORCEPROP 2 LAST CDS_LIB mstr_standard
J 0
(-2850 3125);
PAINT MONO (-2850 3125);
DISPLAY INVISIBLE (-2850 3125);
FORCEPROP 1 LAST BODY_TYPE PLUMBING
J 2
(-2850 3075);
DISPLAY 1.595745 (-2850 3075);
PAINT GREEN (-2850 3075);
DISPLAY INVISIBLE (-2850 3075);
FORCEPROP 1 LAST HDL_TAP TRUE
J 2
(-3175 3000);
DISPLAY 1.595745 (-3175 3000);
PAINT GREEN (-3175 3000);
DISPLAY INVISIBLE (-3175 3000);
FORCEPROP 1 LAST PATH I130
J 2
(-2848 3125);
DISPLAY 0.872340 (-2848 3125);
PAINT GREEN (-2848 3125);
DISPLAY INVISIBLE (-2848 3125);
FORCEADD TAP..6
R 2
(-2850 3175);
FORCEPROP 3 LASTPIN (-2900 3175) SIG_NAME M_K_DQS_DN<6>
J 0
(-2890 3185);
DISPLAY 0.659574 (-2890 3185);
PAINT MONO (-2890 3185);
DISPLAY INVISIBLE (-2890 3185);
FORCEPROP 1 LASTPIN (-2900 3175) BN 6
J 2
(-2848 3183);
DISPLAY 0.617021 (-2848 3183);
PAINT GREEN (-2848 3183);
FORCEPROP 2 LAST CDS_LIB mstr_standard
J 0
(-2850 3175);
PAINT MONO (-2850 3175);
DISPLAY INVISIBLE (-2850 3175);
FORCEPROP 1 LAST BODY_TYPE PLUMBING
J 2
(-2850 3125);
DISPLAY 1.595745 (-2850 3125);
PAINT GREEN (-2850 3125);
DISPLAY INVISIBLE (-2850 3125);
FORCEPROP 1 LAST HDL_TAP TRUE
J 2
(-3175 3050);
DISPLAY 1.595745 (-3175 3050);
PAINT GREEN (-3175 3050);
DISPLAY INVISIBLE (-3175 3050);
FORCEPROP 1 LAST PATH I131
J 2
(-2848 3175);
DISPLAY 0.872340 (-2848 3175);
PAINT GREEN (-2848 3175);
DISPLAY INVISIBLE (-2848 3175);
FORCEADD TAP..6
R 2
(-2850 3225);
FORCEPROP 3 LASTPIN (-2900 3225) SIG_NAME M_K_DQS_DN<7>
J 0
(-2890 3235);
DISPLAY 0.659574 (-2890 3235);
PAINT MONO (-2890 3235);
DISPLAY INVISIBLE (-2890 3235);
FORCEPROP 1 LASTPIN (-2900 3225) BN 7
J 2
(-2848 3233);
DISPLAY 0.617021 (-2848 3233);
PAINT GREEN (-2848 3233);
FORCEPROP 2 LAST CDS_LIB mstr_standard
J 0
(-2850 3225);
PAINT MONO (-2850 3225);
DISPLAY INVISIBLE (-2850 3225);
FORCEPROP 1 LAST BODY_TYPE PLUMBING
J 2
(-2850 3175);
DISPLAY 1.595745 (-2850 3175);
PAINT GREEN (-2850 3175);
DISPLAY INVISIBLE (-2850 3175);
FORCEPROP 1 LAST HDL_TAP TRUE
J 2
(-3175 3100);
DISPLAY 1.595745 (-3175 3100);
PAINT GREEN (-3175 3100);
DISPLAY INVISIBLE (-3175 3100);
FORCEPROP 1 LAST PATH I132
J 2
(-2848 3225);
DISPLAY 0.872340 (-2848 3225);
PAINT GREEN (-2848 3225);
DISPLAY INVISIBLE (-2848 3225);
FORCEADD TAP..6
R 2
(-2850 3275);
FORCEPROP 3 LASTPIN (-2900 3275) SIG_NAME M_K_DQS_DN<8>
J 0
(-2890 3285);
DISPLAY 0.659574 (-2890 3285);
PAINT MONO (-2890 3285);
DISPLAY INVISIBLE (-2890 3285);
FORCEPROP 1 LASTPIN (-2900 3275) BN 8
J 2
(-2848 3283);
DISPLAY 0.617021 (-2848 3283);
PAINT GREEN (-2848 3283);
FORCEPROP 2 LAST CDS_LIB mstr_standard
J 0
(-2850 3275);
PAINT MONO (-2850 3275);
DISPLAY INVISIBLE (-2850 3275);
FORCEPROP 1 LAST BODY_TYPE PLUMBING
J 2
(-2850 3225);
DISPLAY 1.595745 (-2850 3225);
PAINT GREEN (-2850 3225);
DISPLAY INVISIBLE (-2850 3225);
FORCEPROP 1 LAST HDL_TAP TRUE
J 2
(-3175 3150);
DISPLAY 1.595745 (-3175 3150);
PAINT GREEN (-3175 3150);
DISPLAY INVISIBLE (-3175 3150);
FORCEPROP 1 LAST PATH I133
J 2
(-2848 3275);
DISPLAY 0.872340 (-2848 3275);
PAINT GREEN (-2848 3275);
DISPLAY INVISIBLE (-2848 3275);
FORCEADD TAP..6
R 2
(-2850 3325);
FORCEPROP 3 LASTPIN (-2900 3325) SIG_NAME M_K_DQS_DN<9>
J 0
(-2890 3335);
DISPLAY 0.659574 (-2890 3335);
PAINT MONO (-2890 3335);
DISPLAY INVISIBLE (-2890 3335);
FORCEPROP 1 LASTPIN (-2900 3325) BN 9
J 2
(-2848 3333);
DISPLAY 0.617021 (-2848 3333);
PAINT GREEN (-2848 3333);
FORCEPROP 2 LAST CDS_LIB mstr_standard
J 0
(-2850 3325);
PAINT MONO (-2850 3325);
DISPLAY INVISIBLE (-2850 3325);
FORCEPROP 1 LAST BODY_TYPE PLUMBING
J 2
(-2850 3275);
DISPLAY 1.595745 (-2850 3275);
PAINT GREEN (-2850 3275);
DISPLAY INVISIBLE (-2850 3275);
FORCEPROP 1 LAST HDL_TAP TRUE
J 2
(-3175 3200);
DISPLAY 1.595745 (-3175 3200);
PAINT GREEN (-3175 3200);
DISPLAY INVISIBLE (-3175 3200);
FORCEPROP 1 LAST PATH I134
J 2
(-2848 3325);
DISPLAY 0.872340 (-2848 3325);
PAINT GREEN (-2848 3325);
DISPLAY INVISIBLE (-2848 3325);
FORCEADD TAP..6
R 2
(-2850 3375);
FORCEPROP 3 LASTPIN (-2900 3375) SIG_NAME M_K_DQS_DN<10>
J 0
(-2890 3385);
DISPLAY 0.659574 (-2890 3385);
PAINT MONO (-2890 3385);
DISPLAY INVISIBLE (-2890 3385);
FORCEPROP 1 LASTPIN (-2900 3375) BN 10
J 2
(-2848 3383);
DISPLAY 0.617021 (-2848 3383);
PAINT GREEN (-2848 3383);
FORCEPROP 2 LAST CDS_LIB mstr_standard
J 0
(-2850 3375);
PAINT MONO (-2850 3375);
DISPLAY INVISIBLE (-2850 3375);
FORCEPROP 1 LAST BODY_TYPE PLUMBING
J 2
(-2850 3325);
DISPLAY 1.595745 (-2850 3325);
PAINT GREEN (-2850 3325);
DISPLAY INVISIBLE (-2850 3325);
FORCEPROP 1 LAST HDL_TAP TRUE
J 2
(-3175 3250);
DISPLAY 1.595745 (-3175 3250);
PAINT GREEN (-3175 3250);
DISPLAY INVISIBLE (-3175 3250);
FORCEPROP 1 LAST PATH I135
J 2
(-2848 3375);
DISPLAY 0.872340 (-2848 3375);
PAINT GREEN (-2848 3375);
DISPLAY INVISIBLE (-2848 3375);
FORCEADD TAP..6
R 2
(-2850 3475);
FORCEPROP 3 LASTPIN (-2900 3475) SIG_NAME M_K_DQS_DN<12>
J 0
(-2890 3485);
DISPLAY 0.659574 (-2890 3485);
PAINT MONO (-2890 3485);
DISPLAY INVISIBLE (-2890 3485);
FORCEPROP 1 LASTPIN (-2900 3475) BN 12
J 2
(-2848 3483);
DISPLAY 0.617021 (-2848 3483);
PAINT GREEN (-2848 3483);
FORCEPROP 2 LAST CDS_LIB mstr_standard
J 0
(-2850 3475);
PAINT MONO (-2850 3475);
DISPLAY INVISIBLE (-2850 3475);
FORCEPROP 1 LAST BODY_TYPE PLUMBING
J 2
(-2850 3425);
DISPLAY 1.595745 (-2850 3425);
PAINT GREEN (-2850 3425);
DISPLAY INVISIBLE (-2850 3425);
FORCEPROP 1 LAST HDL_TAP TRUE
J 2
(-3175 3350);
DISPLAY 1.595745 (-3175 3350);
PAINT GREEN (-3175 3350);
DISPLAY INVISIBLE (-3175 3350);
FORCEPROP 1 LAST PATH I136
J 2
(-2848 3475);
DISPLAY 0.872340 (-2848 3475);
PAINT GREEN (-2848 3475);
DISPLAY INVISIBLE (-2848 3475);
FORCEADD TAP..6
R 2
(-2850 3425);
FORCEPROP 3 LASTPIN (-2900 3425) SIG_NAME M_K_DQS_DN<11>
J 0
(-2890 3435);
DISPLAY 0.659574 (-2890 3435);
PAINT MONO (-2890 3435);
DISPLAY INVISIBLE (-2890 3435);
FORCEPROP 1 LASTPIN (-2900 3425) BN 11
J 2
(-2848 3433);
DISPLAY 0.617021 (-2848 3433);
PAINT GREEN (-2848 3433);
FORCEPROP 2 LAST CDS_LIB mstr_standard
J 0
(-2850 3425);
PAINT MONO (-2850 3425);
DISPLAY INVISIBLE (-2850 3425);
FORCEPROP 1 LAST BODY_TYPE PLUMBING
J 2
(-2850 3375);
DISPLAY 1.595745 (-2850 3375);
PAINT GREEN (-2850 3375);
DISPLAY INVISIBLE (-2850 3375);
FORCEPROP 1 LAST HDL_TAP TRUE
J 2
(-3175 3300);
DISPLAY 1.595745 (-3175 3300);
PAINT GREEN (-3175 3300);
DISPLAY INVISIBLE (-3175 3300);
FORCEPROP 1 LAST PATH I137
J 2
(-2848 3425);
DISPLAY 0.872340 (-2848 3425);
PAINT GREEN (-2848 3425);
DISPLAY INVISIBLE (-2848 3425);
FORCEADD TAP..6
R 2
(-2850 3625);
FORCEPROP 3 LASTPIN (-2900 3625) SIG_NAME M_K_DQS_DN<15>
J 0
(-2890 3635);
DISPLAY 0.659574 (-2890 3635);
PAINT MONO (-2890 3635);
DISPLAY INVISIBLE (-2890 3635);
FORCEPROP 1 LASTPIN (-2900 3625) BN 15
J 2
(-2848 3633);
DISPLAY 0.617021 (-2848 3633);
PAINT GREEN (-2848 3633);
FORCEPROP 2 LAST CDS_LIB mstr_standard
J 0
(-2850 3625);
PAINT MONO (-2850 3625);
DISPLAY INVISIBLE (-2850 3625);
FORCEPROP 1 LAST BODY_TYPE PLUMBING
J 2
(-2850 3575);
DISPLAY 1.595745 (-2850 3575);
PAINT GREEN (-2850 3575);
DISPLAY INVISIBLE (-2850 3575);
FORCEPROP 1 LAST HDL_TAP TRUE
J 2
(-3175 3500);
DISPLAY 1.595745 (-3175 3500);
PAINT GREEN (-3175 3500);
DISPLAY INVISIBLE (-3175 3500);
FORCEPROP 1 LAST PATH I138
J 2
(-2848 3625);
DISPLAY 0.872340 (-2848 3625);
PAINT GREEN (-2848 3625);
DISPLAY INVISIBLE (-2848 3625);
FORCEADD TAP..6
R 2
(-2850 3575);
FORCEPROP 3 LASTPIN (-2900 3575) SIG_NAME M_K_DQS_DN<14>
J 0
(-2890 3585);
DISPLAY 0.659574 (-2890 3585);
PAINT MONO (-2890 3585);
DISPLAY INVISIBLE (-2890 3585);
FORCEPROP 1 LASTPIN (-2900 3575) BN 14
J 2
(-2848 3583);
DISPLAY 0.617021 (-2848 3583);
PAINT GREEN (-2848 3583);
FORCEPROP 2 LAST CDS_LIB mstr_standard
J 0
(-2850 3575);
PAINT MONO (-2850 3575);
DISPLAY INVISIBLE (-2850 3575);
FORCEPROP 1 LAST BODY_TYPE PLUMBING
J 2
(-2850 3525);
DISPLAY 1.595745 (-2850 3525);
PAINT GREEN (-2850 3525);
DISPLAY INVISIBLE (-2850 3525);
FORCEPROP 1 LAST HDL_TAP TRUE
J 2
(-3175 3450);
DISPLAY 1.595745 (-3175 3450);
PAINT GREEN (-3175 3450);
DISPLAY INVISIBLE (-3175 3450);
FORCEPROP 1 LAST PATH I139
J 2
(-2848 3575);
DISPLAY 0.872340 (-2848 3575);
PAINT GREEN (-2848 3575);
DISPLAY INVISIBLE (-2848 3575);
FORCEADD TAP..6
(-5575 1125);
FORCEPROP 3 LASTPIN (-5525 1125) SIG_NAME M_K_ECC<1>
J 0
(-5515 1135);
DISPLAY 0.659574 (-5515 1135);
PAINT MONO (-5515 1135);
DISPLAY INVISIBLE (-5515 1135);
FORCEPROP 1 LASTPIN (-5525 1125) BN 1
J 0
(-5577 1133);
DISPLAY 0.617021 (-5577 1133);
PAINT GREEN (-5577 1133);
FORCEPROP 2 LAST CDS_LIB mstr_standard
J 0
(-5575 1125);
PAINT MONO (-5575 1125);
DISPLAY INVISIBLE (-5575 1125);
FORCEPROP 1 LAST BODY_TYPE PLUMBING
J 0
(-5575 1075);
DISPLAY 1.595745 (-5575 1075);
PAINT GREEN (-5575 1075);
DISPLAY INVISIBLE (-5575 1075);
FORCEPROP 1 LAST HDL_TAP TRUE
J 0
(-5250 1000);
DISPLAY 1.595745 (-5250 1000);
PAINT GREEN (-5250 1000);
DISPLAY INVISIBLE (-5250 1000);
FORCEPROP 1 LAST PATH I14
J 0
(-5577 1125);
DISPLAY 0.872340 (-5577 1125);
PAINT GREEN (-5577 1125);
DISPLAY INVISIBLE (-5577 1125);
FORCEADD TAP..6
R 2
(-2850 3525);
FORCEPROP 3 LASTPIN (-2900 3525) SIG_NAME M_K_DQS_DN<13>
J 0
(-2890 3535);
DISPLAY 0.659574 (-2890 3535);
PAINT MONO (-2890 3535);
DISPLAY INVISIBLE (-2890 3535);
FORCEPROP 1 LASTPIN (-2900 3525) BN 13
J 2
(-2848 3533);
DISPLAY 0.617021 (-2848 3533);
PAINT GREEN (-2848 3533);
FORCEPROP 2 LAST CDS_LIB mstr_standard
J 0
(-2850 3525);
PAINT MONO (-2850 3525);
DISPLAY INVISIBLE (-2850 3525);
FORCEPROP 1 LAST BODY_TYPE PLUMBING
J 2
(-2850 3475);
DISPLAY 1.595745 (-2850 3475);
PAINT GREEN (-2850 3475);
DISPLAY INVISIBLE (-2850 3475);
FORCEPROP 1 LAST HDL_TAP TRUE
J 2
(-3175 3400);
DISPLAY 1.595745 (-3175 3400);
PAINT GREEN (-3175 3400);
DISPLAY INVISIBLE (-3175 3400);
FORCEPROP 1 LAST PATH I140
J 2
(-2848 3525);
DISPLAY 0.872340 (-2848 3525);
PAINT GREEN (-2848 3525);
DISPLAY INVISIBLE (-2848 3525);
FORCEADD TAP..6
R 2
(-2850 3675);
FORCEPROP 3 LASTPIN (-2900 3675) SIG_NAME M_K_DQS_DN<16>
J 0
(-2890 3685);
DISPLAY 0.659574 (-2890 3685);
PAINT MONO (-2890 3685);
DISPLAY INVISIBLE (-2890 3685);
FORCEPROP 1 LASTPIN (-2900 3675) BN 16
J 2
(-2848 3683);
DISPLAY 0.617021 (-2848 3683);
PAINT GREEN (-2848 3683);
FORCEPROP 2 LAST CDS_LIB mstr_standard
J 0
(-2850 3675);
PAINT MONO (-2850 3675);
DISPLAY INVISIBLE (-2850 3675);
FORCEPROP 1 LAST BODY_TYPE PLUMBING
J 2
(-2850 3625);
DISPLAY 1.595745 (-2850 3625);
PAINT GREEN (-2850 3625);
DISPLAY INVISIBLE (-2850 3625);
FORCEPROP 1 LAST HDL_TAP TRUE
J 2
(-3175 3550);
DISPLAY 1.595745 (-3175 3550);
PAINT GREEN (-3175 3550);
DISPLAY INVISIBLE (-3175 3550);
FORCEPROP 1 LAST PATH I141
J 2
(-2848 3675);
DISPLAY 0.872340 (-2848 3675);
PAINT GREEN (-2848 3675);
DISPLAY INVISIBLE (-2848 3675);
FORCEADD TAP..6
R 2
(-2850 3725);
FORCEPROP 3 LASTPIN (-2900 3725) SIG_NAME M_K_DQS_DN<17>
J 0
(-2890 3735);
DISPLAY 0.659574 (-2890 3735);
PAINT MONO (-2890 3735);
DISPLAY INVISIBLE (-2890 3735);
FORCEPROP 1 LASTPIN (-2900 3725) BN 17
J 2
(-2848 3733);
DISPLAY 0.617021 (-2848 3733);
PAINT GREEN (-2848 3733);
FORCEPROP 2 LAST CDS_LIB mstr_standard
J 0
(-2850 3725);
PAINT MONO (-2850 3725);
DISPLAY INVISIBLE (-2850 3725);
FORCEPROP 1 LAST BODY_TYPE PLUMBING
J 2
(-2850 3675);
DISPLAY 1.595745 (-2850 3675);
PAINT GREEN (-2850 3675);
DISPLAY INVISIBLE (-2850 3675);
FORCEPROP 1 LAST HDL_TAP TRUE
J 2
(-3175 3600);
DISPLAY 1.595745 (-3175 3600);
PAINT GREEN (-3175 3600);
DISPLAY INVISIBLE (-3175 3600);
FORCEPROP 1 LAST PATH I142
J 2
(-2848 3725);
DISPLAY 0.872340 (-2848 3725);
PAINT GREEN (-2848 3725);
DISPLAY INVISIBLE (-2848 3725);
FORCEADD TAP..6
R 2
(-2850 3825);
FORCEPROP 3 LASTPIN (-2900 3825) SIG_NAME M_K_DQS_DP<0>
J 0
(-2890 3835);
DISPLAY 0.659574 (-2890 3835);
PAINT MONO (-2890 3835);
DISPLAY INVISIBLE (-2890 3835);
FORCEPROP 1 LASTPIN (-2900 3825) BN 0
J 2
(-2848 3833);
DISPLAY 0.617021 (-2848 3833);
PAINT GREEN (-2848 3833);
FORCEPROP 2 LAST CDS_LIB mstr_standard
J 0
(-2850 3825);
PAINT MONO (-2850 3825);
DISPLAY INVISIBLE (-2850 3825);
FORCEPROP 1 LAST BODY_TYPE PLUMBING
J 2
(-2850 3775);
DISPLAY 1.595745 (-2850 3775);
PAINT GREEN (-2850 3775);
DISPLAY INVISIBLE (-2850 3775);
FORCEPROP 1 LAST HDL_TAP TRUE
J 2
(-3175 3700);
DISPLAY 1.595745 (-3175 3700);
PAINT GREEN (-3175 3700);
DISPLAY INVISIBLE (-3175 3700);
FORCEPROP 1 LAST PATH I143
J 2
(-2848 3825);
DISPLAY 0.872340 (-2848 3825);
PAINT GREEN (-2848 3825);
DISPLAY INVISIBLE (-2848 3825);
FORCEADD TAP..6
R 2
(-2850 3875);
FORCEPROP 3 LASTPIN (-2900 3875) SIG_NAME M_K_DQS_DP<1>
J 0
(-2890 3885);
DISPLAY 0.659574 (-2890 3885);
PAINT MONO (-2890 3885);
DISPLAY INVISIBLE (-2890 3885);
FORCEPROP 1 LASTPIN (-2900 3875) BN 1
J 2
(-2848 3883);
DISPLAY 0.617021 (-2848 3883);
PAINT GREEN (-2848 3883);
FORCEPROP 2 LAST CDS_LIB mstr_standard
J 0
(-2850 3875);
PAINT MONO (-2850 3875);
DISPLAY INVISIBLE (-2850 3875);
FORCEPROP 1 LAST BODY_TYPE PLUMBING
J 2
(-2850 3825);
DISPLAY 1.595745 (-2850 3825);
PAINT GREEN (-2850 3825);
DISPLAY INVISIBLE (-2850 3825);
FORCEPROP 1 LAST HDL_TAP TRUE
J 2
(-3175 3750);
DISPLAY 1.595745 (-3175 3750);
PAINT GREEN (-3175 3750);
DISPLAY INVISIBLE (-3175 3750);
FORCEPROP 1 LAST PATH I144
J 2
(-2848 3875);
DISPLAY 0.872340 (-2848 3875);
PAINT GREEN (-2848 3875);
DISPLAY INVISIBLE (-2848 3875);
FORCEADD TAP..6
R 2
(-2850 3925);
FORCEPROP 3 LASTPIN (-2900 3925) SIG_NAME M_K_DQS_DP<2>
J 0
(-2890 3935);
DISPLAY 0.659574 (-2890 3935);
PAINT MONO (-2890 3935);
DISPLAY INVISIBLE (-2890 3935);
FORCEPROP 1 LASTPIN (-2900 3925) BN 2
J 2
(-2848 3933);
DISPLAY 0.617021 (-2848 3933);
PAINT GREEN (-2848 3933);
FORCEPROP 2 LAST CDS_LIB mstr_standard
J 0
(-2850 3925);
PAINT MONO (-2850 3925);
DISPLAY INVISIBLE (-2850 3925);
FORCEPROP 1 LAST BODY_TYPE PLUMBING
J 2
(-2850 3875);
DISPLAY 1.595745 (-2850 3875);
PAINT GREEN (-2850 3875);
DISPLAY INVISIBLE (-2850 3875);
FORCEPROP 1 LAST HDL_TAP TRUE
J 2
(-3175 3800);
DISPLAY 1.595745 (-3175 3800);
PAINT GREEN (-3175 3800);
DISPLAY INVISIBLE (-3175 3800);
FORCEPROP 1 LAST PATH I145
J 2
(-2848 3925);
DISPLAY 0.872340 (-2848 3925);
PAINT GREEN (-2848 3925);
DISPLAY INVISIBLE (-2848 3925);
FORCEADD TAP..6
R 2
(-2850 3975);
FORCEPROP 3 LASTPIN (-2900 3975) SIG_NAME M_K_DQS_DP<3>
J 0
(-2890 3985);
DISPLAY 0.659574 (-2890 3985);
PAINT MONO (-2890 3985);
DISPLAY INVISIBLE (-2890 3985);
FORCEPROP 1 LASTPIN (-2900 3975) BN 3
J 2
(-2848 3983);
DISPLAY 0.617021 (-2848 3983);
PAINT GREEN (-2848 3983);
FORCEPROP 2 LAST CDS_LIB mstr_standard
J 0
(-2850 3975);
PAINT MONO (-2850 3975);
DISPLAY INVISIBLE (-2850 3975);
FORCEPROP 1 LAST BODY_TYPE PLUMBING
J 2
(-2850 3925);
DISPLAY 1.595745 (-2850 3925);
PAINT GREEN (-2850 3925);
DISPLAY INVISIBLE (-2850 3925);
FORCEPROP 1 LAST HDL_TAP TRUE
J 2
(-3175 3850);
DISPLAY 1.595745 (-3175 3850);
PAINT GREEN (-3175 3850);
DISPLAY INVISIBLE (-3175 3850);
FORCEPROP 1 LAST PATH I146
J 2
(-2848 3975);
DISPLAY 0.872340 (-2848 3975);
PAINT GREEN (-2848 3975);
DISPLAY INVISIBLE (-2848 3975);
FORCEADD OFFPAGE..2
(-2000 525);
FORCEPROP 2 LAST $XR1 84 
J 0
(-1721 525);
DISPLAY 0.638298 (-1721 525);
PAINT MONO (-1721 525);
FORCEPROP 2 LAST $XR0 83 
J 0
(-1811 525);
DISPLAY 0.638298 (-1811 525);
PAINT MONO (-1811 525);
FORCEPROP 2 LAST CDS_LIB mstr_standard
J 0
(-2000 525);
PAINT MONO (-2000 525);
DISPLAY INVISIBLE (-2000 525);
FORCEPROP 1 LAST OFFPAGE TRUE
J 0
(-1675 400);
DISPLAY 1.170213 (-1675 400);
PAINT GREEN (-1675 400);
DISPLAY INVISIBLE (-1675 400);
FORCEPROP 1 LAST COMMENT_BODY TRUE
J 0
(-2045 430);
DISPLAY 1.170213 (-2045 430);
PAINT GREEN (-2045 430);
DISPLAY INVISIBLE (-2045 430);
FORCEPROP 2 LAST PATH I147
J 0
(-1825 600);
DISPLAY 1.021277 (-1825 600);
PAINT ORANGE (-1825 600);
DISPLAY INVISIBLE (-1825 600);
FORCEADD OFFPAGE..4
(-2000 575);
FORCEPROP 2 LAST $XR1 84 
J 0
(-1724 575);
DISPLAY 0.638298 (-1724 575);
PAINT MONO (-1724 575);
FORCEPROP 2 LAST $XR0 83 
J 0
(-1814 575);
DISPLAY 0.638298 (-1814 575);
PAINT MONO (-1814 575);
FORCEPROP 2 LAST CDS_LIB mstr_standard
J 0
(-2000 575);
PAINT MONO (-2000 575);
DISPLAY INVISIBLE (-2000 575);
FORCEPROP 1 LAST OFFPAGE TRUE
J 0
(-1675 450);
DISPLAY 1.170213 (-1675 450);
PAINT GREEN (-1675 450);
DISPLAY INVISIBLE (-1675 450);
FORCEPROP 1 LAST COMMENT_BODY TRUE
J 0
(-2025 475);
DISPLAY 1.170213 (-2025 475);
PAINT GREEN (-2025 475);
DISPLAY INVISIBLE (-2025 475);
FORCEPROP 2 LAST PATH I148
J 0
(-1825 650);
DISPLAY 1.021277 (-1825 650);
PAINT ORANGE (-1825 650);
DISPLAY INVISIBLE (-1825 650);
FORCEADD OFFPAGE..2
(-2000 625);
FORCEPROP 2 LAST $XR1 84 
J 0
(-1721 625);
DISPLAY 0.638298 (-1721 625);
PAINT MONO (-1721 625);
FORCEPROP 2 LAST $XR0 83 
J 0
(-1811 625);
DISPLAY 0.638298 (-1811 625);
PAINT MONO (-1811 625);
FORCEPROP 2 LAST CDS_LIB mstr_standard
J 0
(-2000 625);
PAINT MONO (-2000 625);
DISPLAY INVISIBLE (-2000 625);
FORCEPROP 1 LAST OFFPAGE TRUE
J 0
(-1675 500);
DISPLAY 1.170213 (-1675 500);
PAINT GREEN (-1675 500);
DISPLAY INVISIBLE (-1675 500);
FORCEPROP 1 LAST COMMENT_BODY TRUE
J 0
(-2045 530);
DISPLAY 1.170213 (-2045 530);
PAINT GREEN (-2045 530);
DISPLAY INVISIBLE (-2045 530);
FORCEPROP 2 LAST PATH I149
J 0
(-1825 700);
DISPLAY 1.021277 (-1825 700);
PAINT ORANGE (-1825 700);
DISPLAY INVISIBLE (-1825 700);
FORCEADD TAP..6
(-5575 1175);
FORCEPROP 3 LASTPIN (-5525 1175) SIG_NAME M_K_ECC<2>
J 0
(-5515 1185);
DISPLAY 0.659574 (-5515 1185);
PAINT MONO (-5515 1185);
DISPLAY INVISIBLE (-5515 1185);
FORCEPROP 1 LASTPIN (-5525 1175) BN 2
J 0
(-5577 1183);
DISPLAY 0.617021 (-5577 1183);
PAINT GREEN (-5577 1183);
FORCEPROP 2 LAST CDS_LIB mstr_standard
J 0
(-5575 1175);
PAINT MONO (-5575 1175);
DISPLAY INVISIBLE (-5575 1175);
FORCEPROP 1 LAST BODY_TYPE PLUMBING
J 0
(-5575 1125);
DISPLAY 1.595745 (-5575 1125);
PAINT GREEN (-5575 1125);
DISPLAY INVISIBLE (-5575 1125);
FORCEPROP 1 LAST HDL_TAP TRUE
J 0
(-5250 1050);
DISPLAY 1.595745 (-5250 1050);
PAINT GREEN (-5250 1050);
DISPLAY INVISIBLE (-5250 1050);
FORCEPROP 1 LAST PATH I15
J 0
(-5577 1175);
DISPLAY 0.872340 (-5577 1175);
PAINT GREEN (-5577 1175);
DISPLAY INVISIBLE (-5577 1175);
FORCEADD OFFPAGE..2
(-2000 825);
FORCEPROP 2 LAST $XR1 84 
J 0
(-1721 825);
DISPLAY 0.638298 (-1721 825);
PAINT MONO (-1721 825);
FORCEPROP 2 LAST $XR0 83 
J 0
(-1811 825);
DISPLAY 0.638298 (-1811 825);
PAINT MONO (-1811 825);
FORCEPROP 2 LAST CDS_LIB mstr_standard
J 0
(-2000 825);
PAINT MONO (-2000 825);
DISPLAY INVISIBLE (-2000 825);
FORCEPROP 1 LAST OFFPAGE TRUE
J 0
(-1675 700);
DISPLAY 1.170213 (-1675 700);
PAINT GREEN (-1675 700);
DISPLAY INVISIBLE (-1675 700);
FORCEPROP 1 LAST COMMENT_BODY TRUE
J 0
(-2045 730);
DISPLAY 1.170213 (-2045 730);
PAINT GREEN (-2045 730);
DISPLAY INVISIBLE (-2045 730);
FORCEPROP 2 LAST PATH I150
J 0
(-1825 900);
DISPLAY 1.021277 (-1825 900);
PAINT ORANGE (-1825 900);
DISPLAY INVISIBLE (-1825 900);
FORCEADD OFFPAGE..2
(-2000 925);
FORCEPROP 2 LAST $XR1 84 
J 0
(-1721 925);
DISPLAY 0.638298 (-1721 925);
PAINT MONO (-1721 925);
FORCEPROP 2 LAST $XR0 83 
J 0
(-1811 925);
DISPLAY 0.638298 (-1811 925);
PAINT MONO (-1811 925);
FORCEPROP 2 LAST CDS_LIB mstr_standard
J 0
(-2000 925);
PAINT MONO (-2000 925);
DISPLAY INVISIBLE (-2000 925);
FORCEPROP 1 LAST OFFPAGE TRUE
J 0
(-1675 800);
DISPLAY 1.170213 (-1675 800);
PAINT GREEN (-1675 800);
DISPLAY INVISIBLE (-1675 800);
FORCEPROP 1 LAST COMMENT_BODY TRUE
J 0
(-2045 830);
DISPLAY 1.170213 (-2045 830);
PAINT GREEN (-2045 830);
DISPLAY INVISIBLE (-2045 830);
FORCEPROP 2 LAST PATH I151
J 0
(-1825 1000);
DISPLAY 1.021277 (-1825 1000);
PAINT ORANGE (-1825 1000);
DISPLAY INVISIBLE (-1825 1000);
FORCEADD OFFPAGE..2
(-2000 1375);
FORCEPROP 2 LAST $XR1 84 
J 0
(-1721 1375);
DISPLAY 0.638298 (-1721 1375);
PAINT MONO (-1721 1375);
FORCEPROP 2 LAST $XR0 83 
J 0
(-1811 1375);
DISPLAY 0.638298 (-1811 1375);
PAINT MONO (-1811 1375);
FORCEPROP 2 LAST CDS_LIB mstr_standard
J 0
(-2000 1375);
PAINT MONO (-2000 1375);
DISPLAY INVISIBLE (-2000 1375);
FORCEPROP 1 LAST OFFPAGE TRUE
J 0
(-1675 1250);
DISPLAY 1.170213 (-1675 1250);
PAINT GREEN (-1675 1250);
DISPLAY INVISIBLE (-1675 1250);
FORCEPROP 1 LAST COMMENT_BODY TRUE
J 0
(-2045 1280);
DISPLAY 1.170213 (-2045 1280);
PAINT GREEN (-2045 1280);
DISPLAY INVISIBLE (-2045 1280);
FORCEPROP 2 LAST PATH I152
J 0
(-1825 1450);
DISPLAY 1.021277 (-1825 1450);
PAINT ORANGE (-1825 1450);
DISPLAY INVISIBLE (-1825 1450);
FORCEADD OFFPAGE..2
(-2000 1625);
FORCEPROP 2 LAST $XR1 84 
J 0
(-1721 1625);
DISPLAY 0.638298 (-1721 1625);
PAINT MONO (-1721 1625);
FORCEPROP 2 LAST $XR0 83 
J 0
(-1811 1625);
DISPLAY 0.638298 (-1811 1625);
PAINT MONO (-1811 1625);
FORCEPROP 2 LAST CDS_LIB mstr_standard
J 0
(-2000 1625);
PAINT MONO (-2000 1625);
DISPLAY INVISIBLE (-2000 1625);
FORCEPROP 1 LAST OFFPAGE TRUE
J 0
(-1675 1500);
DISPLAY 1.170213 (-1675 1500);
PAINT GREEN (-1675 1500);
DISPLAY INVISIBLE (-1675 1500);
FORCEPROP 1 LAST COMMENT_BODY TRUE
J 0
(-2045 1530);
DISPLAY 1.170213 (-2045 1530);
PAINT GREEN (-2045 1530);
DISPLAY INVISIBLE (-2045 1530);
FORCEPROP 2 LAST PATH I153
J 0
(-1825 1700);
DISPLAY 1.021277 (-1825 1700);
PAINT ORANGE (-1825 1700);
DISPLAY INVISIBLE (-1825 1700);
FORCEADD OFFPAGE..2
(-2000 1875);
FORCEPROP 2 LAST $XR1 84 
J 0
(-1721 1875);
DISPLAY 0.638298 (-1721 1875);
PAINT MONO (-1721 1875);
FORCEPROP 2 LAST $XR0 83 
J 0
(-1811 1875);
DISPLAY 0.638298 (-1811 1875);
PAINT MONO (-1811 1875);
FORCEPROP 2 LAST CDS_LIB mstr_standard
J 0
(-2000 1875);
PAINT MONO (-2000 1875);
DISPLAY INVISIBLE (-2000 1875);
FORCEPROP 1 LAST OFFPAGE TRUE
J 0
(-1675 1750);
DISPLAY 1.170213 (-1675 1750);
PAINT GREEN (-1675 1750);
DISPLAY INVISIBLE (-1675 1750);
FORCEPROP 1 LAST COMMENT_BODY TRUE
J 0
(-2045 1780);
DISPLAY 1.170213 (-2045 1780);
PAINT GREEN (-2045 1780);
DISPLAY INVISIBLE (-2045 1780);
FORCEPROP 2 LAST PATH I154
J 0
(-1825 1950);
DISPLAY 1.021277 (-1825 1950);
PAINT ORANGE (-1825 1950);
DISPLAY INVISIBLE (-1825 1950);
FORCEADD OFFPAGE..2
(-2000 2825);
FORCEPROP 2 LAST $XR1 84 
J 0
(-1721 2825);
DISPLAY 0.638298 (-1721 2825);
PAINT MONO (-1721 2825);
FORCEPROP 2 LAST $XR0 83 
J 0
(-1811 2825);
DISPLAY 0.638298 (-1811 2825);
PAINT MONO (-1811 2825);
FORCEPROP 2 LAST CDS_LIB mstr_standard
J 0
(-2000 2825);
PAINT MONO (-2000 2825);
DISPLAY INVISIBLE (-2000 2825);
FORCEPROP 1 LAST OFFPAGE TRUE
J 0
(-1675 2700);
DISPLAY 1.170213 (-1675 2700);
PAINT GREEN (-1675 2700);
DISPLAY INVISIBLE (-1675 2700);
FORCEPROP 1 LAST COMMENT_BODY TRUE
J 0
(-2045 2730);
DISPLAY 1.170213 (-2045 2730);
PAINT GREEN (-2045 2730);
DISPLAY INVISIBLE (-2045 2730);
FORCEPROP 2 LAST PATH I155
J 0
(-1825 2900);
DISPLAY 1.021277 (-1825 2900);
PAINT ORANGE (-1825 2900);
DISPLAY INVISIBLE (-1825 2900);
FORCEADD OFFPAGE..3
(-2000 3775);
FORCEPROP 2 LAST $XR1 84 
J 0
(-1696 3775);
DISPLAY 0.638298 (-1696 3775);
PAINT MONO (-1696 3775);
FORCEPROP 2 LAST $XR0 83 
J 0
(-1786 3775);
DISPLAY 0.638298 (-1786 3775);
PAINT MONO (-1786 3775);
FORCEPROP 2 LAST CDS_LIB mstr_standard
J 0
(-2000 3775);
PAINT MONO (-2000 3775);
DISPLAY INVISIBLE (-2000 3775);
FORCEPROP 1 LAST OFFPAGE TRUE
J 0
(-1675 3650);
DISPLAY 1.170213 (-1675 3650);
PAINT GREEN (-1675 3650);
DISPLAY INVISIBLE (-1675 3650);
FORCEPROP 1 LAST COMMENT_BODY TRUE
J 0
(-2050 3675);
DISPLAY 1.170213 (-2050 3675);
PAINT GREEN (-2050 3675);
DISPLAY INVISIBLE (-2050 3675);
FORCEPROP 2 LAST PATH I156
J 0
(-1800 3850);
DISPLAY 1.021277 (-1800 3850);
PAINT ORANGE (-1800 3850);
DISPLAY INVISIBLE (-1800 3850);
FORCEADD TAP..6
R 2
(-2850 4025);
FORCEPROP 3 LASTPIN (-2900 4025) SIG_NAME M_K_DQS_DP<4>
J 0
(-2890 4035);
DISPLAY 0.659574 (-2890 4035);
PAINT MONO (-2890 4035);
DISPLAY INVISIBLE (-2890 4035);
FORCEPROP 1 LASTPIN (-2900 4025) BN 4
J 2
(-2848 4033);
DISPLAY 0.617021 (-2848 4033);
PAINT GREEN (-2848 4033);
FORCEPROP 2 LAST CDS_LIB mstr_standard
J 0
(-2850 4025);
PAINT MONO (-2850 4025);
DISPLAY INVISIBLE (-2850 4025);
FORCEPROP 1 LAST BODY_TYPE PLUMBING
J 2
(-2850 3975);
DISPLAY 1.595745 (-2850 3975);
PAINT GREEN (-2850 3975);
DISPLAY INVISIBLE (-2850 3975);
FORCEPROP 1 LAST HDL_TAP TRUE
J 2
(-3175 3900);
DISPLAY 1.595745 (-3175 3900);
PAINT GREEN (-3175 3900);
DISPLAY INVISIBLE (-3175 3900);
FORCEPROP 1 LAST PATH I157
J 2
(-2848 4025);
DISPLAY 0.872340 (-2848 4025);
PAINT GREEN (-2848 4025);
DISPLAY INVISIBLE (-2848 4025);
FORCEADD TAP..6
R 2
(-2850 4125);
FORCEPROP 3 LASTPIN (-2900 4125) SIG_NAME M_K_DQS_DP<6>
J 0
(-2890 4135);
DISPLAY 0.659574 (-2890 4135);
PAINT MONO (-2890 4135);
DISPLAY INVISIBLE (-2890 4135);
FORCEPROP 1 LASTPIN (-2900 4125) BN 6
J 2
(-2848 4133);
DISPLAY 0.617021 (-2848 4133);
PAINT GREEN (-2848 4133);
FORCEPROP 2 LAST CDS_LIB mstr_standard
J 0
(-2850 4125);
PAINT MONO (-2850 4125);
DISPLAY INVISIBLE (-2850 4125);
FORCEPROP 1 LAST BODY_TYPE PLUMBING
J 2
(-2850 4075);
DISPLAY 1.595745 (-2850 4075);
PAINT GREEN (-2850 4075);
DISPLAY INVISIBLE (-2850 4075);
FORCEPROP 1 LAST HDL_TAP TRUE
J 2
(-3175 4000);
DISPLAY 1.595745 (-3175 4000);
PAINT GREEN (-3175 4000);
DISPLAY INVISIBLE (-3175 4000);
FORCEPROP 1 LAST PATH I158
J 2
(-2848 4125);
DISPLAY 0.872340 (-2848 4125);
PAINT GREEN (-2848 4125);
DISPLAY INVISIBLE (-2848 4125);
FORCEADD TAP..6
R 2
(-2850 4075);
FORCEPROP 3 LASTPIN (-2900 4075) SIG_NAME M_K_DQS_DP<5>
J 0
(-2890 4085);
DISPLAY 0.659574 (-2890 4085);
PAINT MONO (-2890 4085);
DISPLAY INVISIBLE (-2890 4085);
FORCEPROP 1 LASTPIN (-2900 4075) BN 5
J 2
(-2848 4083);
DISPLAY 0.617021 (-2848 4083);
PAINT GREEN (-2848 4083);
FORCEPROP 2 LAST CDS_LIB mstr_standard
J 0
(-2850 4075);
PAINT MONO (-2850 4075);
DISPLAY INVISIBLE (-2850 4075);
FORCEPROP 1 LAST BODY_TYPE PLUMBING
J 2
(-2850 4025);
DISPLAY 1.595745 (-2850 4025);
PAINT GREEN (-2850 4025);
DISPLAY INVISIBLE (-2850 4025);
FORCEPROP 1 LAST HDL_TAP TRUE
J 2
(-3175 3950);
DISPLAY 1.595745 (-3175 3950);
PAINT GREEN (-3175 3950);
DISPLAY INVISIBLE (-3175 3950);
FORCEPROP 1 LAST PATH I159
J 2
(-2848 4075);
DISPLAY 0.872340 (-2848 4075);
PAINT GREEN (-2848 4075);
DISPLAY INVISIBLE (-2848 4075);
FORCEADD TAP..6
(-5575 1275);
FORCEPROP 3 LASTPIN (-5525 1275) SIG_NAME M_K_ECC<4>
J 0
(-5515 1285);
DISPLAY 0.659574 (-5515 1285);
PAINT MONO (-5515 1285);
DISPLAY INVISIBLE (-5515 1285);
FORCEPROP 1 LASTPIN (-5525 1275) BN 4
J 0
(-5577 1283);
DISPLAY 0.617021 (-5577 1283);
PAINT GREEN (-5577 1283);
FORCEPROP 2 LAST CDS_LIB mstr_standard
J 0
(-5575 1275);
PAINT MONO (-5575 1275);
DISPLAY INVISIBLE (-5575 1275);
FORCEPROP 1 LAST BODY_TYPE PLUMBING
J 0
(-5575 1225);
DISPLAY 1.595745 (-5575 1225);
PAINT GREEN (-5575 1225);
DISPLAY INVISIBLE (-5575 1225);
FORCEPROP 1 LAST HDL_TAP TRUE
J 0
(-5250 1150);
DISPLAY 1.595745 (-5250 1150);
PAINT GREEN (-5250 1150);
DISPLAY INVISIBLE (-5250 1150);
FORCEPROP 1 LAST PATH I16
J 0
(-5577 1275);
DISPLAY 0.872340 (-5577 1275);
PAINT GREEN (-5577 1275);
DISPLAY INVISIBLE (-5577 1275);
FORCEADD TAP..6
R 2
(-2850 4175);
FORCEPROP 3 LASTPIN (-2900 4175) SIG_NAME M_K_DQS_DP<7>
J 0
(-2890 4185);
DISPLAY 0.659574 (-2890 4185);
PAINT MONO (-2890 4185);
DISPLAY INVISIBLE (-2890 4185);
FORCEPROP 1 LASTPIN (-2900 4175) BN 7
J 2
(-2848 4183);
DISPLAY 0.617021 (-2848 4183);
PAINT GREEN (-2848 4183);
FORCEPROP 2 LAST CDS_LIB mstr_standard
J 0
(-2850 4175);
PAINT MONO (-2850 4175);
DISPLAY INVISIBLE (-2850 4175);
FORCEPROP 1 LAST BODY_TYPE PLUMBING
J 2
(-2850 4125);
DISPLAY 1.595745 (-2850 4125);
PAINT GREEN (-2850 4125);
DISPLAY INVISIBLE (-2850 4125);
FORCEPROP 1 LAST HDL_TAP TRUE
J 2
(-3175 4050);
DISPLAY 1.595745 (-3175 4050);
PAINT GREEN (-3175 4050);
DISPLAY INVISIBLE (-3175 4050);
FORCEPROP 1 LAST PATH I160
J 2
(-2848 4175);
DISPLAY 0.872340 (-2848 4175);
PAINT GREEN (-2848 4175);
DISPLAY INVISIBLE (-2848 4175);
FORCEADD TAP..6
R 2
(-2850 4225);
FORCEPROP 3 LASTPIN (-2900 4225) SIG_NAME M_K_DQS_DP<8>
J 0
(-2890 4235);
DISPLAY 0.659574 (-2890 4235);
PAINT MONO (-2890 4235);
DISPLAY INVISIBLE (-2890 4235);
FORCEPROP 1 LASTPIN (-2900 4225) BN 8
J 2
(-2848 4233);
DISPLAY 0.617021 (-2848 4233);
PAINT GREEN (-2848 4233);
FORCEPROP 2 LAST CDS_LIB mstr_standard
J 0
(-2850 4225);
PAINT MONO (-2850 4225);
DISPLAY INVISIBLE (-2850 4225);
FORCEPROP 1 LAST BODY_TYPE PLUMBING
J 2
(-2850 4175);
DISPLAY 1.595745 (-2850 4175);
PAINT GREEN (-2850 4175);
DISPLAY INVISIBLE (-2850 4175);
FORCEPROP 1 LAST HDL_TAP TRUE
J 2
(-3175 4100);
DISPLAY 1.595745 (-3175 4100);
PAINT GREEN (-3175 4100);
DISPLAY INVISIBLE (-3175 4100);
FORCEPROP 1 LAST PATH I161
J 2
(-2848 4225);
DISPLAY 0.872340 (-2848 4225);
PAINT GREEN (-2848 4225);
DISPLAY INVISIBLE (-2848 4225);
FORCEADD TAP..6
R 2
(-2850 4275);
FORCEPROP 3 LASTPIN (-2900 4275) SIG_NAME M_K_DQS_DP<9>
J 0
(-2890 4285);
DISPLAY 0.659574 (-2890 4285);
PAINT MONO (-2890 4285);
DISPLAY INVISIBLE (-2890 4285);
FORCEPROP 1 LASTPIN (-2900 4275) BN 9
J 2
(-2848 4283);
DISPLAY 0.617021 (-2848 4283);
PAINT GREEN (-2848 4283);
FORCEPROP 2 LAST CDS_LIB mstr_standard
J 0
(-2850 4275);
PAINT MONO (-2850 4275);
DISPLAY INVISIBLE (-2850 4275);
FORCEPROP 1 LAST BODY_TYPE PLUMBING
J 2
(-2850 4225);
DISPLAY 1.595745 (-2850 4225);
PAINT GREEN (-2850 4225);
DISPLAY INVISIBLE (-2850 4225);
FORCEPROP 1 LAST HDL_TAP TRUE
J 2
(-3175 4150);
DISPLAY 1.595745 (-3175 4150);
PAINT GREEN (-3175 4150);
DISPLAY INVISIBLE (-3175 4150);
FORCEPROP 1 LAST PATH I162
J 2
(-2848 4275);
DISPLAY 0.872340 (-2848 4275);
PAINT GREEN (-2848 4275);
DISPLAY INVISIBLE (-2848 4275);
FORCEADD TAP..6
R 2
(-2850 4325);
FORCEPROP 3 LASTPIN (-2900 4325) SIG_NAME M_K_DQS_DP<10>
J 0
(-2890 4335);
DISPLAY 0.659574 (-2890 4335);
PAINT MONO (-2890 4335);
DISPLAY INVISIBLE (-2890 4335);
FORCEPROP 1 LASTPIN (-2900 4325) BN 10
J 2
(-2848 4333);
DISPLAY 0.617021 (-2848 4333);
PAINT GREEN (-2848 4333);
FORCEPROP 2 LAST CDS_LIB mstr_standard
J 0
(-2850 4325);
PAINT MONO (-2850 4325);
DISPLAY INVISIBLE (-2850 4325);
FORCEPROP 1 LAST BODY_TYPE PLUMBING
J 2
(-2850 4275);
DISPLAY 1.595745 (-2850 4275);
PAINT GREEN (-2850 4275);
DISPLAY INVISIBLE (-2850 4275);
FORCEPROP 1 LAST HDL_TAP TRUE
J 2
(-3175 4200);
DISPLAY 1.595745 (-3175 4200);
PAINT GREEN (-3175 4200);
DISPLAY INVISIBLE (-3175 4200);
FORCEPROP 1 LAST PATH I163
J 2
(-2848 4325);
DISPLAY 0.872340 (-2848 4325);
PAINT GREEN (-2848 4325);
DISPLAY INVISIBLE (-2848 4325);
FORCEADD TAP..6
R 2
(-2850 4375);
FORCEPROP 3 LASTPIN (-2900 4375) SIG_NAME M_K_DQS_DP<11>
J 0
(-2890 4385);
DISPLAY 0.659574 (-2890 4385);
PAINT MONO (-2890 4385);
DISPLAY INVISIBLE (-2890 4385);
FORCEPROP 1 LASTPIN (-2900 4375) BN 11
J 2
(-2848 4383);
DISPLAY 0.617021 (-2848 4383);
PAINT GREEN (-2848 4383);
FORCEPROP 2 LAST CDS_LIB mstr_standard
J 0
(-2850 4375);
PAINT MONO (-2850 4375);
DISPLAY INVISIBLE (-2850 4375);
FORCEPROP 1 LAST BODY_TYPE PLUMBING
J 2
(-2850 4325);
DISPLAY 1.595745 (-2850 4325);
PAINT GREEN (-2850 4325);
DISPLAY INVISIBLE (-2850 4325);
FORCEPROP 1 LAST HDL_TAP TRUE
J 2
(-3175 4250);
DISPLAY 1.595745 (-3175 4250);
PAINT GREEN (-3175 4250);
DISPLAY INVISIBLE (-3175 4250);
FORCEPROP 1 LAST PATH I164
J 2
(-2848 4375);
DISPLAY 0.872340 (-2848 4375);
PAINT GREEN (-2848 4375);
DISPLAY INVISIBLE (-2848 4375);
FORCEADD TAP..6
R 2
(-2850 4525);
FORCEPROP 3 LASTPIN (-2900 4525) SIG_NAME M_K_DQS_DP<14>
J 0
(-2890 4535);
DISPLAY 0.659574 (-2890 4535);
PAINT MONO (-2890 4535);
DISPLAY INVISIBLE (-2890 4535);
FORCEPROP 1 LASTPIN (-2900 4525) BN 14
J 2
(-2848 4533);
DISPLAY 0.617021 (-2848 4533);
PAINT GREEN (-2848 4533);
FORCEPROP 2 LAST CDS_LIB mstr_standard
J 0
(-2850 4525);
PAINT MONO (-2850 4525);
DISPLAY INVISIBLE (-2850 4525);
FORCEPROP 1 LAST BODY_TYPE PLUMBING
J 2
(-2850 4475);
DISPLAY 1.595745 (-2850 4475);
PAINT GREEN (-2850 4475);
DISPLAY INVISIBLE (-2850 4475);
FORCEPROP 1 LAST HDL_TAP TRUE
J 2
(-3175 4400);
DISPLAY 1.595745 (-3175 4400);
PAINT GREEN (-3175 4400);
DISPLAY INVISIBLE (-3175 4400);
FORCEPROP 1 LAST PATH I165
J 2
(-2848 4525);
DISPLAY 0.872340 (-2848 4525);
PAINT GREEN (-2848 4525);
DISPLAY INVISIBLE (-2848 4525);
FORCEADD TAP..6
R 2
(-2850 4475);
FORCEPROP 3 LASTPIN (-2900 4475) SIG_NAME M_K_DQS_DP<13>
J 0
(-2890 4485);
DISPLAY 0.659574 (-2890 4485);
PAINT MONO (-2890 4485);
DISPLAY INVISIBLE (-2890 4485);
FORCEPROP 1 LASTPIN (-2900 4475) BN 13
J 2
(-2848 4483);
DISPLAY 0.617021 (-2848 4483);
PAINT GREEN (-2848 4483);
FORCEPROP 2 LAST CDS_LIB mstr_standard
J 0
(-2850 4475);
PAINT MONO (-2850 4475);
DISPLAY INVISIBLE (-2850 4475);
FORCEPROP 1 LAST BODY_TYPE PLUMBING
J 2
(-2850 4425);
DISPLAY 1.595745 (-2850 4425);
PAINT GREEN (-2850 4425);
DISPLAY INVISIBLE (-2850 4425);
FORCEPROP 1 LAST HDL_TAP TRUE
J 2
(-3175 4350);
DISPLAY 1.595745 (-3175 4350);
PAINT GREEN (-3175 4350);
DISPLAY INVISIBLE (-3175 4350);
FORCEPROP 1 LAST PATH I166
J 2
(-2848 4475);
DISPLAY 0.872340 (-2848 4475);
PAINT GREEN (-2848 4475);
DISPLAY INVISIBLE (-2848 4475);
FORCEADD TAP..6
R 2
(-2850 4425);
FORCEPROP 3 LASTPIN (-2900 4425) SIG_NAME M_K_DQS_DP<12>
J 0
(-2890 4435);
DISPLAY 0.659574 (-2890 4435);
PAINT MONO (-2890 4435);
DISPLAY INVISIBLE (-2890 4435);
FORCEPROP 1 LASTPIN (-2900 4425) BN 12
J 2
(-2848 4433);
DISPLAY 0.617021 (-2848 4433);
PAINT GREEN (-2848 4433);
FORCEPROP 2 LAST CDS_LIB mstr_standard
J 0
(-2850 4425);
PAINT MONO (-2850 4425);
DISPLAY INVISIBLE (-2850 4425);
FORCEPROP 1 LAST BODY_TYPE PLUMBING
J 2
(-2850 4375);
DISPLAY 1.595745 (-2850 4375);
PAINT GREEN (-2850 4375);
DISPLAY INVISIBLE (-2850 4375);
FORCEPROP 1 LAST HDL_TAP TRUE
J 2
(-3175 4300);
DISPLAY 1.595745 (-3175 4300);
PAINT GREEN (-3175 4300);
DISPLAY INVISIBLE (-3175 4300);
FORCEPROP 1 LAST PATH I167
J 2
(-2848 4425);
DISPLAY 0.872340 (-2848 4425);
PAINT GREEN (-2848 4425);
DISPLAY INVISIBLE (-2848 4425);
FORCEADD TAP..6
R 2
(-2850 4575);
FORCEPROP 3 LASTPIN (-2900 4575) SIG_NAME M_K_DQS_DP<15>
J 0
(-2890 4585);
DISPLAY 0.659574 (-2890 4585);
PAINT MONO (-2890 4585);
DISPLAY INVISIBLE (-2890 4585);
FORCEPROP 1 LASTPIN (-2900 4575) BN 15
J 2
(-2848 4583);
DISPLAY 0.617021 (-2848 4583);
PAINT GREEN (-2848 4583);
FORCEPROP 2 LAST CDS_LIB mstr_standard
J 0
(-2850 4575);
PAINT MONO (-2850 4575);
DISPLAY INVISIBLE (-2850 4575);
FORCEPROP 1 LAST BODY_TYPE PLUMBING
J 2
(-2850 4525);
DISPLAY 1.595745 (-2850 4525);
PAINT GREEN (-2850 4525);
DISPLAY INVISIBLE (-2850 4525);
FORCEPROP 1 LAST HDL_TAP TRUE
J 2
(-3175 4450);
DISPLAY 1.595745 (-3175 4450);
PAINT GREEN (-3175 4450);
DISPLAY INVISIBLE (-3175 4450);
FORCEPROP 1 LAST PATH I168
J 2
(-2848 4575);
DISPLAY 0.872340 (-2848 4575);
PAINT GREEN (-2848 4575);
DISPLAY INVISIBLE (-2848 4575);
FORCEADD TAP..6
R 2
(-2850 4625);
FORCEPROP 3 LASTPIN (-2900 4625) SIG_NAME M_K_DQS_DP<16>
J 0
(-2890 4635);
DISPLAY 0.659574 (-2890 4635);
PAINT MONO (-2890 4635);
DISPLAY INVISIBLE (-2890 4635);
FORCEPROP 1 LASTPIN (-2900 4625) BN 16
J 2
(-2848 4633);
DISPLAY 0.617021 (-2848 4633);
PAINT GREEN (-2848 4633);
FORCEPROP 2 LAST CDS_LIB mstr_standard
J 0
(-2850 4625);
PAINT MONO (-2850 4625);
DISPLAY INVISIBLE (-2850 4625);
FORCEPROP 1 LAST BODY_TYPE PLUMBING
J 2
(-2850 4575);
DISPLAY 1.595745 (-2850 4575);
PAINT GREEN (-2850 4575);
DISPLAY INVISIBLE (-2850 4575);
FORCEPROP 1 LAST HDL_TAP TRUE
J 2
(-3175 4500);
DISPLAY 1.595745 (-3175 4500);
PAINT GREEN (-3175 4500);
DISPLAY INVISIBLE (-3175 4500);
FORCEPROP 1 LAST PATH I169
J 2
(-2848 4625);
DISPLAY 0.872340 (-2848 4625);
PAINT GREEN (-2848 4625);
DISPLAY INVISIBLE (-2848 4625);
FORCEADD TAP..6
(-5575 1225);
FORCEPROP 3 LASTPIN (-5525 1225) SIG_NAME M_K_ECC<3>
J 0
(-5515 1235);
DISPLAY 0.659574 (-5515 1235);
PAINT MONO (-5515 1235);
DISPLAY INVISIBLE (-5515 1235);
FORCEPROP 1 LASTPIN (-5525 1225) BN 3
J 0
(-5577 1233);
DISPLAY 0.617021 (-5577 1233);
PAINT GREEN (-5577 1233);
FORCEPROP 2 LAST CDS_LIB mstr_standard
J 0
(-5575 1225);
PAINT MONO (-5575 1225);
DISPLAY INVISIBLE (-5575 1225);
FORCEPROP 1 LAST BODY_TYPE PLUMBING
J 0
(-5575 1175);
DISPLAY 1.595745 (-5575 1175);
PAINT GREEN (-5575 1175);
DISPLAY INVISIBLE (-5575 1175);
FORCEPROP 1 LAST HDL_TAP TRUE
J 0
(-5250 1100);
DISPLAY 1.595745 (-5250 1100);
PAINT GREEN (-5250 1100);
DISPLAY INVISIBLE (-5250 1100);
FORCEPROP 1 LAST PATH I17
J 0
(-5577 1225);
DISPLAY 0.872340 (-5577 1225);
PAINT GREEN (-5577 1225);
DISPLAY INVISIBLE (-5577 1225);
FORCEADD TAP..6
R 2
(-2850 4675);
FORCEPROP 3 LASTPIN (-2900 4675) SIG_NAME M_K_DQS_DP<17>
J 0
(-2890 4685);
DISPLAY 0.659574 (-2890 4685);
PAINT MONO (-2890 4685);
DISPLAY INVISIBLE (-2890 4685);
FORCEPROP 1 LASTPIN (-2900 4675) BN 17
J 2
(-2848 4683);
DISPLAY 0.617021 (-2848 4683);
PAINT GREEN (-2848 4683);
FORCEPROP 2 LAST CDS_LIB mstr_standard
J 2
(-2850 4675);
PAINT MONO (-2850 4675);
DISPLAY INVISIBLE (-2850 4675);
FORCEPROP 1 LAST BODY_TYPE PLUMBING
J 2
(-2850 4625);
DISPLAY 1.595745 (-2850 4625);
PAINT GREEN (-2850 4625);
DISPLAY INVISIBLE (-2850 4625);
FORCEPROP 1 LAST HDL_TAP TRUE
J 2
(-3175 4550);
DISPLAY 1.595745 (-3175 4550);
PAINT GREEN (-3175 4550);
DISPLAY INVISIBLE (-3175 4550);
FORCEPROP 1 LAST PATH I170
J 2
(-2848 4675);
DISPLAY 0.872340 (-2848 4675);
PAINT GREEN (-2848 4675);
DISPLAY INVISIBLE (-2848 4675);
FORCEADD OFFPAGE..3
(-2000 4750);
FORCEPROP 2 LAST $XR1 84 
J 0
(-1696 4750);
DISPLAY 0.638298 (-1696 4750);
PAINT MONO (-1696 4750);
FORCEPROP 2 LAST $XR0 83 
J 0
(-1786 4750);
DISPLAY 0.638298 (-1786 4750);
PAINT MONO (-1786 4750);
FORCEPROP 2 LAST CDS_LIB mstr_standard
J 0
(-2000 4750);
PAINT MONO (-2000 4750);
DISPLAY INVISIBLE (-2000 4750);
FORCEPROP 1 LAST OFFPAGE TRUE
J 0
(-1675 4625);
DISPLAY 1.170213 (-1675 4625);
PAINT GREEN (-1675 4625);
DISPLAY INVISIBLE (-1675 4625);
FORCEPROP 1 LAST COMMENT_BODY TRUE
J 0
(-2050 4650);
DISPLAY 1.170213 (-2050 4650);
PAINT GREEN (-2050 4650);
DISPLAY INVISIBLE (-2050 4650);
FORCEPROP 2 LAST PATH I171
J 0
(-1800 4825);
DISPLAY 1.021277 (-1800 4825);
PAINT ORANGE (-1800 4825);
DISPLAY INVISIBLE (-1800 4825);
FORCEADD SKX_EXT_B..6
(-4175 2575);
FORCEPROP 1 LAST LOCATION U2D1
J 0
(-4975 4925);
DISPLAY 0.617021 (-4975 4925);
PAINT AQUA (-4975 4925);
FORCEPROP 1 LAST PART_NUMBER TBD
J 0
(-4975 325);
DISPLAY 0.617021 (-4975 325);
PAINT BLUE (-4975 325);
FORCEPROP 1 LAST MATERIAL IC
J 0
(-4975 4875);
DISPLAY 0.617021 (-4975 4875);
PAINT SKYBLUE (-4975 4875);
FORCEPROP 2 LASTPIN (-3325 525) $PN ED53
J 0
(-3315 535);
DISPLAY 0.617021 (-3315 535);
PAINT ORANGE (-3315 535);
FORCEPROP 2 LASTPIN (-3325 1575) $PN EA48
J 0
(-3315 1585);
DISPLAY 0.617021 (-3315 1585);
PAINT ORANGE (-3315 1585);
FORCEPROP 2 LASTPIN (-3325 1525) $PN EA50
J 0
(-3315 1535);
DISPLAY 0.617021 (-3315 1535);
PAINT ORANGE (-3315 1535);
FORCEPROP 2 LASTPIN (-3325 1475) $PN EE48
J 0
(-3315 1485);
DISPLAY 0.617021 (-3315 1485);
PAINT ORANGE (-3315 1485);
FORCEPROP 2 LASTPIN (-3325 1425) $PN EE50
J 0
(-3315 1435);
DISPLAY 0.617021 (-3315 1435);
PAINT ORANGE (-3315 1435);
FORCEPROP 2 LASTPIN (-3325 2775) $PN EA46
J 0
(-3315 2785);
DISPLAY 0.617021 (-3315 2785);
PAINT ORANGE (-3315 2785);
FORCEPROP 2 LASTPIN (-3325 2725) $PN EA52
J 0
(-3315 2735);
DISPLAY 0.617021 (-3315 2735);
PAINT ORANGE (-3315 2735);
FORCEPROP 2 LASTPIN (-3325 2675) $PN DV49
J 0
(-3315 2685);
DISPLAY 0.617021 (-3315 2685);
PAINT ORANGE (-3315 2685);
FORCEPROP 2 LASTPIN (-3325 2625) $PN ED51
J 0
(-3315 2635);
DISPLAY 0.617021 (-3315 2635);
PAINT ORANGE (-3315 2635);
FORCEPROP 2 LASTPIN (-3325 2575) $PN DW48
J 0
(-3315 2585);
DISPLAY 0.617021 (-3315 2585);
PAINT ORANGE (-3315 2585);
FORCEPROP 2 LASTPIN (-3325 2525) $PN DT63
J 0
(-3315 2535);
DISPLAY 0.617021 (-3315 2535);
PAINT ORANGE (-3315 2535);
FORCEPROP 2 LASTPIN (-3325 2475) $PN EB61
J 0
(-3315 2485);
DISPLAY 0.617021 (-3315 2485);
PAINT ORANGE (-3315 2485);
FORCEPROP 2 LASTPIN (-3325 2425) $PN DW54
J 0
(-3315 2435);
DISPLAY 0.617021 (-3315 2435);
PAINT ORANGE (-3315 2435);
FORCEPROP 2 LASTPIN (-3325 2375) $PN EF61
J 0
(-3315 2385);
DISPLAY 0.617021 (-3315 2385);
PAINT ORANGE (-3315 2385);
FORCEPROP 2 LASTPIN (-3325 2325) $PN EB59
J 0
(-3315 2335);
DISPLAY 0.617021 (-3315 2335);
PAINT ORANGE (-3315 2335);
FORCEPROP 2 LASTPIN (-3325 2275) $PN EA60
J 0
(-3315 2285);
DISPLAY 0.617021 (-3315 2285);
PAINT ORANGE (-3315 2285);
FORCEPROP 2 LASTPIN (-3325 2225) $PN EE60
J 0
(-3315 2235);
DISPLAY 0.617021 (-3315 2235);
PAINT ORANGE (-3315 2235);
FORCEPROP 2 LASTPIN (-3325 2175) $PN EA58
J 0
(-3315 2185);
DISPLAY 0.617021 (-3315 2185);
PAINT ORANGE (-3315 2185);
FORCEPROP 2 LASTPIN (-3325 2125) $PN ED59
J 0
(-3315 2135);
DISPLAY 0.617021 (-3315 2135);
PAINT ORANGE (-3315 2135);
FORCEPROP 2 LASTPIN (-3325 2075) $PN EB57
J 0
(-3315 2085);
DISPLAY 0.617021 (-3315 2085);
PAINT ORANGE (-3315 2085);
FORCEPROP 2 LASTPIN (-3325 2025) $PN EE58
J 0
(-3315 2035);
DISPLAY 0.617021 (-3315 2035);
PAINT ORANGE (-3315 2035);
FORCEPROP 2 LASTPIN (-3325 1975) $PN ED57
J 0
(-3315 1985);
DISPLAY 0.617021 (-3315 1985);
PAINT ORANGE (-3315 1985);
FORCEPROP 2 LASTPIN (-3325 1925) $PN EB53
J 0
(-3315 1935);
DISPLAY 0.617021 (-3315 1935);
PAINT ORANGE (-3315 1935);
FORCEPROP 2 LASTPIN (-5025 1425) $PN DE66
J 2
(-5035 1435);
DISPLAY 0.617021 (-5035 1435);
PAINT ORANGE (-5035 1435);
FORCEPROP 2 LASTPIN (-5025 1375) $PN DA66
J 2
(-5035 1385);
DISPLAY 0.617021 (-5035 1385);
PAINT ORANGE (-5035 1385);
FORCEPROP 2 LASTPIN (-5025 1325) $PN DD69
J 2
(-5035 1335);
DISPLAY 0.617021 (-5035 1335);
PAINT ORANGE (-5035 1335);
FORCEPROP 2 LASTPIN (-5025 1275) $PN DB69
J 2
(-5035 1285);
DISPLAY 0.617021 (-5035 1285);
PAINT ORANGE (-5035 1285);
FORCEPROP 2 LASTPIN (-5025 1225) $PN DD65
J 2
(-5035 1235);
DISPLAY 0.617021 (-5035 1235);
PAINT ORANGE (-5035 1235);
FORCEPROP 2 LASTPIN (-5025 1175) $PN DB65
J 2
(-5035 1185);
DISPLAY 0.617021 (-5035 1185);
PAINT ORANGE (-5035 1185);
FORCEPROP 2 LASTPIN (-5025 1125) $PN DE68
J 2
(-5035 1135);
DISPLAY 0.617021 (-5035 1135);
PAINT ORANGE (-5035 1135);
FORCEPROP 2 LASTPIN (-5025 1075) $PN DA68
J 2
(-5035 1085);
DISPLAY 0.617021 (-5035 1085);
PAINT ORANGE (-5035 1085);
FORCEPROP 2 LASTPIN (-3325 4675) $PN CY67
J 0
(-3315 4685);
DISPLAY 0.617021 (-3315 4685);
PAINT ORANGE (-3315 4685);
FORCEPROP 2 LASTPIN (-3325 4625) $PN DP23
J 0
(-3315 4635);
DISPLAY 0.617021 (-3315 4635);
PAINT ORANGE (-3315 4635);
FORCEPROP 2 LASTPIN (-3325 4575) $PN DP29
J 0
(-3315 4585);
DISPLAY 0.617021 (-3315 4585);
PAINT ORANGE (-3315 4585);
FORCEPROP 2 LASTPIN (-3325 4525) $PN DM35
J 0
(-3315 4535);
DISPLAY 0.617021 (-3315 4535);
PAINT ORANGE (-3315 4535);
FORCEPROP 2 LASTPIN (-3325 4475) $PN DW38
J 0
(-3315 4485);
DISPLAY 0.617021 (-3315 4485);
PAINT ORANGE (-3315 4485);
FORCEPROP 2 LASTPIN (-3325 4425) $PN DM75
J 0
(-3315 4435);
DISPLAY 0.617021 (-3315 4435);
PAINT ORANGE (-3315 4435);
FORCEPROP 2 LASTPIN (-3325 4375) $PN DP79
J 0
(-3315 4385);
DISPLAY 0.617021 (-3315 4385);
PAINT ORANGE (-3315 4385);
FORCEPROP 2 LASTPIN (-3325 4325) $PN DL84
J 0
(-3315 4335);
DISPLAY 0.617021 (-3315 4335);
PAINT ORANGE (-3315 4335);
FORCEPROP 2 LASTPIN (-3325 4275) $PN CP85
J 0
(-3315 4285);
DISPLAY 0.617021 (-3315 4285);
PAINT ORANGE (-3315 4285);
FORCEPROP 2 LASTPIN (-3325 4225) $PN DD67
J 0
(-3315 4235);
DISPLAY 0.617021 (-3315 4235);
PAINT ORANGE (-3315 4235);
FORCEPROP 2 LASTPIN (-3325 4175) $PN DT23
J 0
(-3315 4185);
DISPLAY 0.617021 (-3315 4185);
PAINT ORANGE (-3315 4185);
FORCEPROP 2 LASTPIN (-3325 4125) $PN DT29
J 0
(-3315 4135);
DISPLAY 0.617021 (-3315 4135);
PAINT ORANGE (-3315 4135);
FORCEPROP 2 LASTPIN (-3325 4075) $PN DT35
J 0
(-3315 4085);
DISPLAY 0.617021 (-3315 4085);
PAINT ORANGE (-3315 4085);
FORCEPROP 2 LASTPIN (-3325 4025) $PN EC38
J 0
(-3315 4035);
DISPLAY 0.617021 (-3315 4035);
PAINT ORANGE (-3315 4035);
FORCEPROP 2 LASTPIN (-3325 3975) $PN DT75
J 0
(-3315 3985);
DISPLAY 0.617021 (-3315 3985);
PAINT ORANGE (-3315 3985);
FORCEPROP 2 LASTPIN (-3325 3925) $PN DM81
J 0
(-3315 3935);
DISPLAY 0.617021 (-3315 3935);
PAINT ORANGE (-3315 3935);
FORCEPROP 2 LASTPIN (-3325 3875) $PN DP85
J 0
(-3315 3885);
DISPLAY 0.617021 (-3315 3885);
PAINT ORANGE (-3315 3885);
FORCEPROP 2 LASTPIN (-3325 3825) $PN CV85
J 0
(-3315 3835);
DISPLAY 0.617021 (-3315 3835);
PAINT ORANGE (-3315 3835);
FORCEPROP 2 LASTPIN (-3325 3725) $PN DB67
J 0
(-3315 3735);
DISPLAY 0.617021 (-3315 3735);
PAINT ORANGE (-3315 3735);
FORCEPROP 2 LASTPIN (-3325 3675) $PN DM23
J 0
(-3315 3685);
DISPLAY 0.617021 (-3315 3685);
PAINT ORANGE (-3315 3685);
FORCEPROP 2 LASTPIN (-3325 3625) $PN DM29
J 0
(-3315 3635);
DISPLAY 0.617021 (-3315 3635);
PAINT ORANGE (-3315 3635);
FORCEPROP 2 LASTPIN (-3325 3575) $PN DP35
J 0
(-3315 3585);
DISPLAY 0.617021 (-3315 3585);
PAINT ORANGE (-3315 3585);
FORCEPROP 2 LASTPIN (-3325 3525) $PN EA38
J 0
(-3315 3535);
DISPLAY 0.617021 (-3315 3535);
PAINT ORANGE (-3315 3535);
FORCEPROP 2 LASTPIN (-3325 3475) $PN DP75
J 0
(-3315 3485);
DISPLAY 0.617021 (-3315 3485);
PAINT ORANGE (-3315 3485);
FORCEPROP 2 LASTPIN (-3325 3425) $PN DN80
J 0
(-3315 3435);
DISPLAY 0.617021 (-3315 3435);
PAINT ORANGE (-3315 3435);
FORCEPROP 2 LASTPIN (-3325 3375) $PN DM85
J 0
(-3315 3385);
DISPLAY 0.617021 (-3315 3385);
PAINT ORANGE (-3315 3385);
FORCEPROP 2 LASTPIN (-3325 3325) $PN CR84
J 0
(-3315 3335);
DISPLAY 0.617021 (-3315 3335);
PAINT ORANGE (-3315 3335);
FORCEPROP 2 LASTPIN (-3325 3275) $PN DF67
J 0
(-3315 3285);
DISPLAY 0.617021 (-3315 3285);
PAINT ORANGE (-3315 3285);
FORCEPROP 2 LASTPIN (-3325 3225) $PN DV23
J 0
(-3315 3235);
DISPLAY 0.617021 (-3315 3235);
PAINT ORANGE (-3315 3235);
FORCEPROP 2 LASTPIN (-3325 3175) $PN DV29
J 0
(-3315 3185);
DISPLAY 0.617021 (-3315 3185);
PAINT ORANGE (-3315 3185);
FORCEPROP 2 LASTPIN (-3325 3125) $PN DV35
J 0
(-3315 3135);
DISPLAY 0.617021 (-3315 3135);
PAINT ORANGE (-3315 3135);
FORCEPROP 2 LASTPIN (-3325 3075) $PN EE38
J 0
(-3315 3085);
DISPLAY 0.617021 (-3315 3085);
PAINT ORANGE (-3315 3085);
FORCEPROP 2 LASTPIN (-3325 3025) $PN DV75
J 0
(-3315 3035);
DISPLAY 0.617021 (-3315 3035);
PAINT ORANGE (-3315 3035);
FORCEPROP 2 LASTPIN (-3325 2975) $PN DL82
J 0
(-3315 2985);
DISPLAY 0.617021 (-3315 2985);
PAINT ORANGE (-3315 2985);
FORCEPROP 2 LASTPIN (-3325 2925) $PN DN84
J 0
(-3315 2935);
DISPLAY 0.617021 (-3315 2935);
PAINT ORANGE (-3315 2935);
FORCEPROP 2 LASTPIN (-3325 2875) $PN CU84
J 0
(-3315 2885);
DISPLAY 0.617021 (-3315 2885);
PAINT ORANGE (-3315 2885);
FORCEPROP 2 LASTPIN (-5025 4675) $PN DW22
J 2
(-5035 4685);
DISPLAY 0.617021 (-5035 4685);
PAINT ORANGE (-5035 4685);
FORCEPROP 2 LASTPIN (-5025 4625) $PN EC22
J 2
(-5035 4635);
DISPLAY 0.617021 (-5035 4635);
PAINT ORANGE (-5035 4635);
FORCEPROP 2 LASTPIN (-5025 4575) $PN DT25
J 2
(-5035 4585);
DISPLAY 0.617021 (-5035 4585);
PAINT ORANGE (-5035 4585);
FORCEPROP 2 LASTPIN (-5025 4525) $PN DP25
J 2
(-5035 4535);
DISPLAY 0.617021 (-5035 4535);
PAINT ORANGE (-5035 4535);
FORCEPROP 2 LASTPIN (-5025 4475) $PN EB21
J 2
(-5035 4485);
DISPLAY 0.617021 (-5035 4485);
PAINT ORANGE (-5035 4485);
FORCEPROP 2 LASTPIN (-5025 4425) $PN DY21
J 2
(-5035 4435);
DISPLAY 0.617021 (-5035 4435);
PAINT ORANGE (-5035 4435);
FORCEPROP 2 LASTPIN (-5025 4375) $PN DU24
J 2
(-5035 4385);
DISPLAY 0.617021 (-5035 4385);
PAINT ORANGE (-5035 4385);
FORCEPROP 2 LASTPIN (-5025 4325) $PN DN24
J 2
(-5035 4335);
DISPLAY 0.617021 (-5035 4335);
PAINT ORANGE (-5035 4335);
FORCEPROP 2 LASTPIN (-5025 4275) $PN DU28
J 2
(-5035 4285);
DISPLAY 0.617021 (-5035 4285);
PAINT ORANGE (-5035 4285);
FORCEPROP 2 LASTPIN (-5025 4225) $PN DN28
J 2
(-5035 4235);
DISPLAY 0.617021 (-5035 4235);
PAINT ORANGE (-5035 4235);
FORCEPROP 2 LASTPIN (-5025 4175) $PN DT31
J 2
(-5035 4185);
DISPLAY 0.617021 (-5035 4185);
PAINT ORANGE (-5035 4185);
FORCEPROP 2 LASTPIN (-5025 4125) $PN DP31
J 2
(-5035 4135);
DISPLAY 0.617021 (-5035 4135);
PAINT ORANGE (-5035 4135);
FORCEPROP 2 LASTPIN (-5025 4075) $PN DT27
J 2
(-5035 4085);
DISPLAY 0.617021 (-5035 4085);
PAINT ORANGE (-5035 4085);
FORCEPROP 2 LASTPIN (-5025 4025) $PN DP27
J 2
(-5035 4035);
DISPLAY 0.617021 (-5035 4035);
PAINT ORANGE (-5035 4035);
FORCEPROP 2 LASTPIN (-5025 3975) $PN DU30
J 2
(-5035 3985);
DISPLAY 0.617021 (-5035 3985);
PAINT ORANGE (-5035 3985);
FORCEPROP 2 LASTPIN (-5025 3925) $PN DN30
J 2
(-5035 3935);
DISPLAY 0.617021 (-5035 3935);
PAINT ORANGE (-5035 3935);
FORCEPROP 2 LASTPIN (-5025 3875) $PN DU34
J 2
(-5035 3885);
DISPLAY 0.617021 (-5035 3885);
PAINT ORANGE (-5035 3885);
FORCEPROP 2 LASTPIN (-5025 3825) $PN DN34
J 2
(-5035 3835);
DISPLAY 0.617021 (-5035 3835);
PAINT ORANGE (-5035 3835);
FORCEPROP 2 LASTPIN (-5025 3775) $PN DT37
J 2
(-5035 3785);
DISPLAY 0.617021 (-5035 3785);
PAINT ORANGE (-5035 3785);
FORCEPROP 2 LASTPIN (-5025 3725) $PN DP37
J 2
(-5035 3735);
DISPLAY 0.617021 (-5035 3735);
PAINT ORANGE (-5035 3735);
FORCEPROP 2 LASTPIN (-5025 3675) $PN DT33
J 2
(-5035 3685);
DISPLAY 0.617021 (-5035 3685);
PAINT ORANGE (-5035 3685);
FORCEPROP 2 LASTPIN (-5025 3625) $PN DP33
J 2
(-5035 3635);
DISPLAY 0.617021 (-5035 3635);
PAINT ORANGE (-5035 3635);
FORCEPROP 2 LASTPIN (-5025 3575) $PN DU36
J 2
(-5035 3585);
DISPLAY 0.617021 (-5035 3585);
PAINT ORANGE (-5035 3585);
FORCEPROP 2 LASTPIN (-5025 3525) $PN DN36
J 2
(-5035 3535);
DISPLAY 0.617021 (-5035 3535);
PAINT ORANGE (-5035 3535);
FORCEPROP 2 LASTPIN (-5025 3475) $PN ED37
J 2
(-5035 3485);
DISPLAY 0.617021 (-5035 3485);
PAINT ORANGE (-5035 3485);
FORCEPROP 2 LASTPIN (-5025 3425) $PN DY37
J 2
(-5035 3435);
DISPLAY 0.617021 (-5035 3435);
PAINT ORANGE (-5035 3435);
FORCEPROP 2 LASTPIN (-5025 3375) $PN EA40
J 2
(-5035 3385);
DISPLAY 0.617021 (-5035 3385);
PAINT ORANGE (-5035 3385);
FORCEPROP 2 LASTPIN (-5025 3325) $PN DY39
J 2
(-5035 3335);
DISPLAY 0.617021 (-5035 3335);
PAINT ORANGE (-5035 3335);
FORCEPROP 2 LASTPIN (-5025 3275) $PN EC36
J 2
(-5035 3285);
DISPLAY 0.617021 (-5035 3285);
PAINT ORANGE (-5035 3285);
FORCEPROP 2 LASTPIN (-5025 3225) $PN EA36
J 2
(-5035 3235);
DISPLAY 0.617021 (-5035 3235);
PAINT ORANGE (-5035 3235);
FORCEPROP 2 LASTPIN (-5025 3175) $PN ED39
J 2
(-5035 3185);
DISPLAY 0.617021 (-5035 3185);
PAINT ORANGE (-5035 3185);
FORCEPROP 2 LASTPIN (-5025 3125) $PN EC40
J 2
(-5035 3135);
DISPLAY 0.617021 (-5035 3135);
PAINT ORANGE (-5035 3135);
FORCEPROP 2 LASTPIN (-5025 3075) $PN DU74
J 2
(-5035 3085);
DISPLAY 0.617021 (-5035 3085);
PAINT ORANGE (-5035 3085);
FORCEPROP 2 LASTPIN (-5025 3025) $PN DN74
J 2
(-5035 3035);
DISPLAY 0.617021 (-5035 3035);
PAINT ORANGE (-5035 3035);
FORCEPROP 2 LASTPIN (-5025 2975) $PN DT77
J 2
(-5035 2985);
DISPLAY 0.617021 (-5035 2985);
PAINT ORANGE (-5035 2985);
FORCEPROP 2 LASTPIN (-5025 2825) $PN DP73
J 2
(-5035 2835);
DISPLAY 0.617021 (-5035 2835);
PAINT ORANGE (-5035 2835);
FORCEPROP 2 LASTPIN (-5025 2775) $PN DU76
J 2
(-5035 2785);
DISPLAY 0.617021 (-5035 2785);
PAINT ORANGE (-5035 2785);
FORCEPROP 2 LASTPIN (-5025 2725) $PN DN76
J 2
(-5035 2735);
DISPLAY 0.617021 (-5035 2735);
PAINT ORANGE (-5035 2735);
FORCEPROP 2 LASTPIN (-5025 2675) $PN DN82
J 2
(-5035 2685);
DISPLAY 0.617021 (-5035 2685);
PAINT ORANGE (-5035 2685);
FORCEPROP 2 LASTPIN (-5025 2625) $PN DR80
J 2
(-5035 2635);
DISPLAY 0.617021 (-5035 2635);
PAINT ORANGE (-5035 2635);
FORCEPROP 2 LASTPIN (-5025 2575) $PN DJ80
J 2
(-5035 2585);
DISPLAY 0.617021 (-5035 2585);
PAINT ORANGE (-5035 2585);
FORCEPROP 2 LASTPIN (-5025 2525) $PN DK79
J 2
(-5035 2535);
DISPLAY 0.617021 (-5035 2535);
PAINT ORANGE (-5035 2535);
FORCEPROP 2 LASTPIN (-5025 2475) $PN DR82
J 2
(-5035 2485);
DISPLAY 0.617021 (-5035 2485);
PAINT ORANGE (-5035 2485);
FORCEPROP 2 LASTPIN (-5025 2425) $PN DT81
J 2
(-5035 2435);
DISPLAY 0.617021 (-5035 2435);
PAINT ORANGE (-5035 2435);
FORCEPROP 2 LASTPIN (-5025 2375) $PN DK81
J 2
(-5035 2385);
DISPLAY 0.617021 (-5035 2385);
PAINT ORANGE (-5035 2385);
FORCEPROP 2 LASTPIN (-5025 2325) $PN DM79
J 2
(-5035 2335);
DISPLAY 0.617021 (-5035 2335);
PAINT ORANGE (-5035 2335);
FORCEPROP 2 LASTPIN (-5025 2275) $PN DV85
J 2
(-5035 2285);
DISPLAY 0.617021 (-5035 2285);
PAINT ORANGE (-5035 2285);
FORCEPROP 2 LASTPIN (-5025 2225) $PN DR84
J 2
(-5035 2235);
DISPLAY 0.617021 (-5035 2235);
PAINT ORANGE (-5035 2235);
FORCEPROP 2 LASTPIN (-5025 2175) $PN DE84
J 2
(-5035 2185);
DISPLAY 0.617021 (-5035 2185);
PAINT ORANGE (-5035 2185);
FORCEPROP 2 LASTPIN (-5025 2125) $PN DD85
J 2
(-5035 2135);
DISPLAY 0.617021 (-5035 2135);
PAINT ORANGE (-5035 2135);
FORCEPROP 2 LASTPIN (-5025 2075) $PN DY83
J 2
(-5035 2085);
DISPLAY 0.617021 (-5035 2085);
PAINT ORANGE (-5035 2085);
FORCEPROP 2 LASTPIN (-5025 2025) $PN DV83
J 2
(-5035 2035);
DISPLAY 0.617021 (-5035 2035);
PAINT ORANGE (-5035 2035);
FORCEPROP 2 LASTPIN (-5025 1975) $PN DH85
J 2
(-5035 1985);
DISPLAY 0.617021 (-5035 1985);
PAINT ORANGE (-5035 1985);
FORCEPROP 2 LASTPIN (-5025 1925) $PN DG84
J 2
(-5035 1935);
DISPLAY 0.617021 (-5035 1935);
PAINT ORANGE (-5035 1935);
FORCEPROP 2 LASTPIN (-5025 1875) $PN CW84
J 2
(-5035 1885);
DISPLAY 0.617021 (-5035 1885);
PAINT ORANGE (-5035 1885);
FORCEPROP 2 LASTPIN (-5025 1825) $PN CW86
J 2
(-5035 1835);
DISPLAY 0.617021 (-5035 1835);
PAINT ORANGE (-5035 1835);
FORCEPROP 2 LASTPIN (-5025 1775) $PN CL86
J 2
(-5035 1785);
DISPLAY 0.617021 (-5035 1785);
PAINT ORANGE (-5035 1785);
FORCEPROP 2 LASTPIN (-5025 1725) $PN CL84
J 2
(-5035 1735);
DISPLAY 0.617021 (-5035 1735);
PAINT ORANGE (-5035 1735);
FORCEPROP 2 LASTPIN (-5025 1675) $PN DA84
J 2
(-5035 1685);
DISPLAY 0.617021 (-5035 1685);
PAINT ORANGE (-5035 1685);
FORCEPROP 2 LASTPIN (-5025 1625) $PN DA86
J 2
(-5035 1635);
DISPLAY 0.617021 (-5035 1635);
PAINT ORANGE (-5035 1635);
FORCEPROP 2 LASTPIN (-5025 1575) $PN CN86
J 2
(-5035 1585);
DISPLAY 0.617021 (-5035 1585);
PAINT ORANGE (-5035 1585);
FORCEPROP 2 LASTPIN (-5025 1525) $PN CN84
J 2
(-5035 1535);
DISPLAY 0.617021 (-5035 1535);
PAINT ORANGE (-5035 1535);
FORCEPROP 2 LASTPIN (-3325 1325) $PN EB45
J 0
(-3315 1335);
DISPLAY 0.617021 (-3315 1335);
PAINT ORANGE (-3315 1335);
FORCEPROP 2 LASTPIN (-3325 1275) $PN DV45
J 0
(-3315 1285);
DISPLAY 0.617021 (-3315 1285);
PAINT ORANGE (-3315 1285);
FORCEPROP 2 LASTPIN (-3325 1225) $PN EB49
J 0
(-3315 1235);
DISPLAY 0.617021 (-3315 1235);
PAINT ORANGE (-3315 1235);
FORCEPROP 2 LASTPIN (-3325 1175) $PN EB51
J 0
(-3315 1185);
DISPLAY 0.617021 (-3315 1185);
PAINT ORANGE (-3315 1185);
FORCEPROP 2 LASTPIN (-3325 1125) $PN EB47
J 0
(-3315 1135);
DISPLAY 0.617021 (-3315 1135);
PAINT ORANGE (-3315 1135);
FORCEPROP 2 LASTPIN (-3325 1075) $PN ED47
J 0
(-3315 1085);
DISPLAY 0.617021 (-3315 1085);
PAINT ORANGE (-3315 1085);
FORCEPROP 2 LASTPIN (-3325 1025) $PN ED49
J 0
(-3315 1035);
DISPLAY 0.617021 (-3315 1035);
PAINT ORANGE (-3315 1035);
FORCEPROP 2 LASTPIN (-3325 975) $PN EF51
J 0
(-3315 985);
DISPLAY 0.617021 (-3315 985);
PAINT ORANGE (-3315 985);
FORCEPROP 2 LASTPIN (-5025 975) $PN EE56
J 2
(-5035 985);
DISPLAY 0.617021 (-5035 985);
PAINT ORANGE (-5035 985);
FORCEPROP 2 LASTPIN (-5025 925) $PN EA56
J 2
(-5035 935);
DISPLAY 0.617021 (-5035 935);
PAINT ORANGE (-5035 935);
FORCEPROP 2 LASTPIN (-5025 875) $PN EE54
J 2
(-5035 885);
DISPLAY 0.617021 (-5035 885);
PAINT ORANGE (-5035 885);
FORCEPROP 2 LASTPIN (-5025 825) $PN EB55
J 2
(-5035 835);
DISPLAY 0.617021 (-5035 835);
PAINT ORANGE (-5035 835);
FORCEPROP 2 LASTPIN (-5025 775) $PN EF57
J 2
(-5035 785);
DISPLAY 0.617021 (-5035 785);
PAINT ORANGE (-5035 785);
FORCEPROP 2 LASTPIN (-5025 725) $PN DW56
J 2
(-5035 735);
DISPLAY 0.617021 (-5035 735);
PAINT ORANGE (-5035 735);
FORCEPROP 2 LASTPIN (-5025 675) $PN EF55
J 2
(-5035 685);
DISPLAY 0.617021 (-5035 685);
PAINT ORANGE (-5035 685);
FORCEPROP 2 LASTPIN (-5025 625) $PN ED55
J 2
(-5035 635);
DISPLAY 0.617021 (-5035 635);
PAINT ORANGE (-5035 635);
FORCEPROP 2 LASTPIN (-3325 1825) $PN EB63
J 0
(-3315 1835);
DISPLAY 0.617021 (-3315 1835);
PAINT ORANGE (-3315 1835);
FORCEPROP 2 LASTPIN (-3325 1775) $PN EA62
J 0
(-3315 1785);
DISPLAY 0.617021 (-3315 1785);
PAINT ORANGE (-3315 1785);
FORCEPROP 2 LASTPIN (-3325 1725) $PN EF63
J 0
(-3315 1735);
DISPLAY 0.617021 (-3315 1735);
PAINT ORANGE (-3315 1735);
FORCEPROP 2 LASTPIN (-3325 1675) $PN EE62
J 0
(-3315 1685);
DISPLAY 0.617021 (-3315 1685);
PAINT ORANGE (-3315 1685);
FORCEPROP 2 LASTPIN (-5025 525) $PN DV47
J 2
(-5035 535);
DISPLAY 0.617021 (-5035 535);
PAINT ORANGE (-5035 535);
FORCEPROP 2 LASTPIN (-3325 875) $PN DW62
J 0
(-3315 885);
DISPLAY 0.617021 (-3315 885);
PAINT ORANGE (-3315 885);
FORCEPROP 2 LASTPIN (-3325 825) $PN ED61
J 0
(-3315 835);
DISPLAY 0.617021 (-3315 835);
PAINT ORANGE (-3315 835);
FORCEPROP 2 LASTPIN (-3325 775) $PN EA54
J 0
(-3315 785);
DISPLAY 0.617021 (-3315 785);
PAINT ORANGE (-3315 785);
FORCEPROP 2 LASTPIN (-3325 725) $PN EE52
J 0
(-3315 735);
DISPLAY 0.617021 (-3315 735);
PAINT ORANGE (-3315 735);
FORCEPROP 2 LASTPIN (-3325 575) $PN ED63
J 0
(-3315 585);
DISPLAY 0.617021 (-3315 585);
PAINT ORANGE (-3315 585);
FORCEPROP 2 LASTPIN (-3325 625) $PN DW60
J 0
(-3315 635);
DISPLAY 0.617021 (-3315 635);
PAINT ORANGE (-3315 635);
FORCEPROP 2 LASTPIN (-5025 2925) $PN DP77
J 2
(-5035 2935);
DISPLAY 0.617021 (-5035 2935);
PAINT ORANGE (-5035 2935);
FORCEPROP 2 LASTPIN (-5025 2875) $PN DT73
J 2
(-5035 2885);
DISPLAY 0.617021 (-5035 2885);
PAINT ORANGE (-5035 2885);
FORCEPROP 1 LAST PACK_TYPE BGA1
J 0
(-4975 4975);
PAINT SKYBLUE (-4975 4975);
DISPLAY INVISIBLE (-4975 4975);
FORCEPROP 2 LAST SEC_TYPE BGA1
J 0
(-4975 4975);
DISPLAY 1.021277 (-4975 4975);
PAINT ORANGE (-4975 4975);
DISPLAY INVISIBLE (-4975 4975);
FORCEPROP 2 LAST CDS_LIB chpset_lib
J 0
(-4175 2575);
PAINT ORANGE (-4175 2575);
DISPLAY INVISIBLE (-4175 2575);
FORCEPROP 2 LAST SEC 6
J 0
(-4975 4975);
DISPLAY 0.680851 (-4975 4975);
PAINT MONO (-4975 4975);
DISPLAY INVISIBLE (-4975 4975);
FORCEPROP 2 LAST CDS_LOCATION U2D1
J 0
(-4975 4925);
DISPLAY 0.617021 (-4975 4925);
PAINT AQUA (-4975 4925);
DISPLAY INVISIBLE (-4975 4925);
FORCEPROP 1 LAST PATH I172
J 0
(-4175 4875);
PAINT GREEN (-4175 4875);
DISPLAY INVISIBLE (-4175 4875);
FORCEADD TAP..6
(-5575 1325);
FORCEPROP 3 LASTPIN (-5525 1325) SIG_NAME M_K_ECC<5>
J 0
(-5515 1335);
DISPLAY 0.659574 (-5515 1335);
PAINT MONO (-5515 1335);
DISPLAY INVISIBLE (-5515 1335);
FORCEPROP 1 LASTPIN (-5525 1325) BN 5
J 0
(-5577 1333);
DISPLAY 0.617021 (-5577 1333);
PAINT GREEN (-5577 1333);
FORCEPROP 2 LAST CDS_LIB mstr_standard
J 0
(-5575 1325);
PAINT MONO (-5575 1325);
DISPLAY INVISIBLE (-5575 1325);
FORCEPROP 1 LAST BODY_TYPE PLUMBING
J 0
(-5575 1275);
DISPLAY 1.595745 (-5575 1275);
PAINT GREEN (-5575 1275);
DISPLAY INVISIBLE (-5575 1275);
FORCEPROP 1 LAST HDL_TAP TRUE
J 0
(-5250 1200);
DISPLAY 1.595745 (-5250 1200);
PAINT GREEN (-5250 1200);
DISPLAY INVISIBLE (-5250 1200);
FORCEPROP 1 LAST PATH I18
J 0
(-5577 1325);
DISPLAY 0.872340 (-5577 1325);
PAINT GREEN (-5577 1325);
DISPLAY INVISIBLE (-5577 1325);
FORCEADD TAP..6
(-5575 1375);
FORCEPROP 3 LASTPIN (-5525 1375) SIG_NAME M_K_ECC<6>
J 0
(-5515 1385);
DISPLAY 0.659574 (-5515 1385);
PAINT MONO (-5515 1385);
DISPLAY INVISIBLE (-5515 1385);
FORCEPROP 1 LASTPIN (-5525 1375) BN 6
J 0
(-5577 1383);
DISPLAY 0.617021 (-5577 1383);
PAINT GREEN (-5577 1383);
FORCEPROP 2 LAST CDS_LIB mstr_standard
J 0
(-5575 1375);
PAINT MONO (-5575 1375);
DISPLAY INVISIBLE (-5575 1375);
FORCEPROP 1 LAST BODY_TYPE PLUMBING
J 0
(-5575 1325);
DISPLAY 1.595745 (-5575 1325);
PAINT GREEN (-5575 1325);
DISPLAY INVISIBLE (-5575 1325);
FORCEPROP 1 LAST HDL_TAP TRUE
J 0
(-5250 1250);
DISPLAY 1.595745 (-5250 1250);
PAINT GREEN (-5250 1250);
DISPLAY INVISIBLE (-5250 1250);
FORCEPROP 1 LAST PATH I19
J 0
(-5577 1375);
DISPLAY 0.872340 (-5577 1375);
PAINT GREEN (-5577 1375);
DISPLAY INVISIBLE (-5577 1375);
FORCEADD OFFPAGE..5
(-6425 825);
FORCEPROP 2 LAST $XR1 84 
J 0
(-6769 825);
DISPLAY 0.638298 (-6769 825);
PAINT MONO (-6769 825);
FORCEPROP 2 LAST $XR0 83 
J 0
(-6679 825);
DISPLAY 0.638298 (-6679 825);
PAINT MONO (-6679 825);
FORCEPROP 2 LAST CDS_LIB mstr_standard
J 0
(-6425 825);
PAINT MONO (-6425 825);
DISPLAY INVISIBLE (-6425 825);
FORCEPROP 1 LAST OFFPAGE TRUE
J 0
(-6100 700);
DISPLAY 1.170213 (-6100 700);
PAINT GREEN (-6100 700);
DISPLAY INVISIBLE (-6100 700);
FORCEPROP 1 LAST COMMENT_BODY TRUE
J 0
(-6325 750);
DISPLAY 1.170213 (-6325 750);
PAINT GREEN (-6325 750);
DISPLAY INVISIBLE (-6325 750);
FORCEPROP 2 LAST PATH I2
J 0
(-6375 900);
DISPLAY 1.021277 (-6375 900);
PAINT ORANGE (-6375 900);
DISPLAY INVISIBLE (-6375 900);
FORCEADD TAP..6
(-5575 1425);
FORCEPROP 3 LASTPIN (-5525 1425) SIG_NAME M_K_ECC<7>
J 0
(-5515 1435);
DISPLAY 0.659574 (-5515 1435);
PAINT MONO (-5515 1435);
DISPLAY INVISIBLE (-5515 1435);
FORCEPROP 1 LASTPIN (-5525 1425) BN 7
J 0
(-5577 1433);
DISPLAY 0.617021 (-5577 1433);
PAINT GREEN (-5577 1433);
FORCEPROP 2 LAST CDS_LIB mstr_standard
J 0
(-5575 1425);
PAINT MONO (-5575 1425);
DISPLAY INVISIBLE (-5575 1425);
FORCEPROP 1 LAST BODY_TYPE PLUMBING
J 0
(-5575 1375);
DISPLAY 1.595745 (-5575 1375);
PAINT GREEN (-5575 1375);
DISPLAY INVISIBLE (-5575 1375);
FORCEPROP 1 LAST HDL_TAP TRUE
J 0
(-5250 1300);
DISPLAY 1.595745 (-5250 1300);
PAINT GREEN (-5250 1300);
DISPLAY INVISIBLE (-5250 1300);
FORCEPROP 1 LAST PATH I20
J 0
(-5577 1425);
DISPLAY 0.872340 (-5577 1425);
PAINT GREEN (-5577 1425);
DISPLAY INVISIBLE (-5577 1425);
FORCEADD TAP..6
(-5575 1525);
FORCEPROP 3 LASTPIN (-5525 1525) SIG_NAME M_K_DQ<0>
J 0
(-5515 1535);
DISPLAY 0.659574 (-5515 1535);
PAINT MONO (-5515 1535);
DISPLAY INVISIBLE (-5515 1535);
FORCEPROP 1 LASTPIN (-5525 1525) BN 0
J 0
(-5577 1533);
DISPLAY 0.617021 (-5577 1533);
PAINT GREEN (-5577 1533);
FORCEPROP 2 LAST CDS_LIB mstr_standard
J 0
(-5575 1525);
PAINT MONO (-5575 1525);
DISPLAY INVISIBLE (-5575 1525);
FORCEPROP 1 LAST BODY_TYPE PLUMBING
J 0
(-5575 1475);
DISPLAY 1.595745 (-5575 1475);
PAINT GREEN (-5575 1475);
DISPLAY INVISIBLE (-5575 1475);
FORCEPROP 1 LAST HDL_TAP TRUE
J 0
(-5250 1400);
DISPLAY 1.595745 (-5250 1400);
PAINT GREEN (-5250 1400);
DISPLAY INVISIBLE (-5250 1400);
FORCEPROP 1 LAST PATH I21
J 0
(-5577 1525);
DISPLAY 0.872340 (-5577 1525);
PAINT GREEN (-5577 1525);
DISPLAY INVISIBLE (-5577 1525);
FORCEADD TAP..6
(-5575 1575);
FORCEPROP 3 LASTPIN (-5525 1575) SIG_NAME M_K_DQ<1>
J 0
(-5515 1585);
DISPLAY 0.659574 (-5515 1585);
PAINT MONO (-5515 1585);
DISPLAY INVISIBLE (-5515 1585);
FORCEPROP 1 LASTPIN (-5525 1575) BN 1
J 0
(-5577 1583);
DISPLAY 0.617021 (-5577 1583);
PAINT GREEN (-5577 1583);
FORCEPROP 2 LAST CDS_LIB mstr_standard
J 0
(-5575 1575);
PAINT MONO (-5575 1575);
DISPLAY INVISIBLE (-5575 1575);
FORCEPROP 1 LAST BODY_TYPE PLUMBING
J 0
(-5575 1525);
DISPLAY 1.595745 (-5575 1525);
PAINT GREEN (-5575 1525);
DISPLAY INVISIBLE (-5575 1525);
FORCEPROP 1 LAST HDL_TAP TRUE
J 0
(-5250 1450);
DISPLAY 1.595745 (-5250 1450);
PAINT GREEN (-5250 1450);
DISPLAY INVISIBLE (-5250 1450);
FORCEPROP 1 LAST PATH I22
J 0
(-5577 1575);
DISPLAY 0.872340 (-5577 1575);
PAINT GREEN (-5577 1575);
DISPLAY INVISIBLE (-5577 1575);
FORCEADD TAP..6
(-5575 1625);
FORCEPROP 3 LASTPIN (-5525 1625) SIG_NAME M_K_DQ<2>
J 0
(-5515 1635);
DISPLAY 0.659574 (-5515 1635);
PAINT MONO (-5515 1635);
DISPLAY INVISIBLE (-5515 1635);
FORCEPROP 1 LASTPIN (-5525 1625) BN 2
J 0
(-5577 1633);
DISPLAY 0.617021 (-5577 1633);
PAINT GREEN (-5577 1633);
FORCEPROP 2 LAST CDS_LIB mstr_standard
J 0
(-5575 1625);
PAINT MONO (-5575 1625);
DISPLAY INVISIBLE (-5575 1625);
FORCEPROP 1 LAST BODY_TYPE PLUMBING
J 0
(-5575 1575);
DISPLAY 1.595745 (-5575 1575);
PAINT GREEN (-5575 1575);
DISPLAY INVISIBLE (-5575 1575);
FORCEPROP 1 LAST HDL_TAP TRUE
J 0
(-5250 1500);
DISPLAY 1.595745 (-5250 1500);
PAINT GREEN (-5250 1500);
DISPLAY INVISIBLE (-5250 1500);
FORCEPROP 1 LAST PATH I23
J 0
(-5577 1625);
DISPLAY 0.872340 (-5577 1625);
PAINT GREEN (-5577 1625);
DISPLAY INVISIBLE (-5577 1625);
FORCEADD TAP..6
(-5575 1675);
FORCEPROP 3 LASTPIN (-5525 1675) SIG_NAME M_K_DQ<3>
J 0
(-5515 1685);
DISPLAY 0.659574 (-5515 1685);
PAINT MONO (-5515 1685);
DISPLAY INVISIBLE (-5515 1685);
FORCEPROP 1 LASTPIN (-5525 1675) BN 3
J 0
(-5577 1683);
DISPLAY 0.617021 (-5577 1683);
PAINT GREEN (-5577 1683);
FORCEPROP 2 LAST CDS_LIB mstr_standard
J 0
(-5575 1675);
PAINT MONO (-5575 1675);
DISPLAY INVISIBLE (-5575 1675);
FORCEPROP 1 LAST BODY_TYPE PLUMBING
J 0
(-5575 1625);
DISPLAY 1.595745 (-5575 1625);
PAINT GREEN (-5575 1625);
DISPLAY INVISIBLE (-5575 1625);
FORCEPROP 1 LAST HDL_TAP TRUE
J 0
(-5250 1550);
DISPLAY 1.595745 (-5250 1550);
PAINT GREEN (-5250 1550);
DISPLAY INVISIBLE (-5250 1550);
FORCEPROP 1 LAST PATH I24
J 0
(-5577 1675);
DISPLAY 0.872340 (-5577 1675);
PAINT GREEN (-5577 1675);
DISPLAY INVISIBLE (-5577 1675);
FORCEADD TAP..6
(-5575 1725);
FORCEPROP 3 LASTPIN (-5525 1725) SIG_NAME M_K_DQ<4>
J 0
(-5515 1735);
DISPLAY 0.659574 (-5515 1735);
PAINT MONO (-5515 1735);
DISPLAY INVISIBLE (-5515 1735);
FORCEPROP 1 LASTPIN (-5525 1725) BN 4
J 0
(-5577 1733);
DISPLAY 0.617021 (-5577 1733);
PAINT GREEN (-5577 1733);
FORCEPROP 2 LAST CDS_LIB mstr_standard
J 0
(-5575 1725);
PAINT MONO (-5575 1725);
DISPLAY INVISIBLE (-5575 1725);
FORCEPROP 1 LAST BODY_TYPE PLUMBING
J 0
(-5575 1675);
DISPLAY 1.595745 (-5575 1675);
PAINT GREEN (-5575 1675);
DISPLAY INVISIBLE (-5575 1675);
FORCEPROP 1 LAST HDL_TAP TRUE
J 0
(-5250 1600);
DISPLAY 1.595745 (-5250 1600);
PAINT GREEN (-5250 1600);
DISPLAY INVISIBLE (-5250 1600);
FORCEPROP 1 LAST PATH I25
J 0
(-5577 1725);
DISPLAY 0.872340 (-5577 1725);
PAINT GREEN (-5577 1725);
DISPLAY INVISIBLE (-5577 1725);
FORCEADD TAP..6
(-5575 1775);
FORCEPROP 3 LASTPIN (-5525 1775) SIG_NAME M_K_DQ<5>
J 0
(-5515 1785);
DISPLAY 0.659574 (-5515 1785);
PAINT MONO (-5515 1785);
DISPLAY INVISIBLE (-5515 1785);
FORCEPROP 1 LASTPIN (-5525 1775) BN 5
J 0
(-5577 1783);
DISPLAY 0.617021 (-5577 1783);
PAINT GREEN (-5577 1783);
FORCEPROP 2 LAST CDS_LIB mstr_standard
J 0
(-5575 1775);
PAINT MONO (-5575 1775);
DISPLAY INVISIBLE (-5575 1775);
FORCEPROP 1 LAST BODY_TYPE PLUMBING
J 0
(-5575 1725);
DISPLAY 1.595745 (-5575 1725);
PAINT GREEN (-5575 1725);
DISPLAY INVISIBLE (-5575 1725);
FORCEPROP 1 LAST HDL_TAP TRUE
J 0
(-5250 1650);
DISPLAY 1.595745 (-5250 1650);
PAINT GREEN (-5250 1650);
DISPLAY INVISIBLE (-5250 1650);
FORCEPROP 1 LAST PATH I26
J 0
(-5577 1775);
DISPLAY 0.872340 (-5577 1775);
PAINT GREEN (-5577 1775);
DISPLAY INVISIBLE (-5577 1775);
FORCEADD TAP..6
(-5575 1825);
FORCEPROP 3 LASTPIN (-5525 1825) SIG_NAME M_K_DQ<6>
J 0
(-5515 1835);
DISPLAY 0.659574 (-5515 1835);
PAINT MONO (-5515 1835);
DISPLAY INVISIBLE (-5515 1835);
FORCEPROP 1 LASTPIN (-5525 1825) BN 6
J 0
(-5577 1833);
DISPLAY 0.617021 (-5577 1833);
PAINT GREEN (-5577 1833);
FORCEPROP 2 LAST CDS_LIB mstr_standard
J 0
(-5575 1825);
PAINT MONO (-5575 1825);
DISPLAY INVISIBLE (-5575 1825);
FORCEPROP 1 LAST BODY_TYPE PLUMBING
J 0
(-5575 1775);
DISPLAY 1.595745 (-5575 1775);
PAINT GREEN (-5575 1775);
DISPLAY INVISIBLE (-5575 1775);
FORCEPROP 1 LAST HDL_TAP TRUE
J 0
(-5250 1700);
DISPLAY 1.595745 (-5250 1700);
PAINT GREEN (-5250 1700);
DISPLAY INVISIBLE (-5250 1700);
FORCEPROP 1 LAST PATH I27
J 0
(-5577 1825);
DISPLAY 0.872340 (-5577 1825);
PAINT GREEN (-5577 1825);
DISPLAY INVISIBLE (-5577 1825);
FORCEADD TAP..6
(-5575 1925);
FORCEPROP 3 LASTPIN (-5525 1925) SIG_NAME M_K_DQ<8>
J 0
(-5515 1935);
DISPLAY 0.659574 (-5515 1935);
PAINT MONO (-5515 1935);
DISPLAY INVISIBLE (-5515 1935);
FORCEPROP 1 LASTPIN (-5525 1925) BN 8
J 0
(-5577 1933);
DISPLAY 0.617021 (-5577 1933);
PAINT GREEN (-5577 1933);
FORCEPROP 2 LAST CDS_LIB mstr_standard
J 0
(-5575 1925);
PAINT MONO (-5575 1925);
DISPLAY INVISIBLE (-5575 1925);
FORCEPROP 1 LAST BODY_TYPE PLUMBING
J 0
(-5575 1875);
DISPLAY 1.595745 (-5575 1875);
PAINT GREEN (-5575 1875);
DISPLAY INVISIBLE (-5575 1875);
FORCEPROP 1 LAST HDL_TAP TRUE
J 0
(-5250 1800);
DISPLAY 1.595745 (-5250 1800);
PAINT GREEN (-5250 1800);
DISPLAY INVISIBLE (-5250 1800);
FORCEPROP 1 LAST PATH I28
J 0
(-5577 1925);
DISPLAY 0.872340 (-5577 1925);
PAINT GREEN (-5577 1925);
DISPLAY INVISIBLE (-5577 1925);
FORCEADD TAP..6
(-5575 1875);
FORCEPROP 3 LASTPIN (-5525 1875) SIG_NAME M_K_DQ<7>
J 0
(-5515 1885);
DISPLAY 0.659574 (-5515 1885);
PAINT MONO (-5515 1885);
DISPLAY INVISIBLE (-5515 1885);
FORCEPROP 1 LASTPIN (-5525 1875) BN 7
J 0
(-5577 1883);
DISPLAY 0.617021 (-5577 1883);
PAINT GREEN (-5577 1883);
FORCEPROP 2 LAST CDS_LIB mstr_standard
J 0
(-5575 1875);
PAINT MONO (-5575 1875);
DISPLAY INVISIBLE (-5575 1875);
FORCEPROP 1 LAST BODY_TYPE PLUMBING
J 0
(-5575 1825);
DISPLAY 1.595745 (-5575 1825);
PAINT GREEN (-5575 1825);
DISPLAY INVISIBLE (-5575 1825);
FORCEPROP 1 LAST HDL_TAP TRUE
J 0
(-5250 1750);
DISPLAY 1.595745 (-5250 1750);
PAINT GREEN (-5250 1750);
DISPLAY INVISIBLE (-5250 1750);
FORCEPROP 1 LAST PATH I29
J 0
(-5577 1875);
DISPLAY 0.872340 (-5577 1875);
PAINT GREEN (-5577 1875);
DISPLAY INVISIBLE (-5577 1875);
FORCEADD OFFPAGE..5
(-6425 1025);
FORCEPROP 2 LAST $XR1 84 
J 0
(-6769 1025);
DISPLAY 0.638298 (-6769 1025);
PAINT MONO (-6769 1025);
FORCEPROP 2 LAST $XR0 83 
J 0
(-6679 1025);
DISPLAY 0.638298 (-6679 1025);
PAINT MONO (-6679 1025);
FORCEPROP 2 LAST CDS_LIB mstr_standard
J 0
(-6425 1025);
PAINT MONO (-6425 1025);
DISPLAY INVISIBLE (-6425 1025);
FORCEPROP 1 LAST OFFPAGE TRUE
J 0
(-6100 900);
DISPLAY 1.170213 (-6100 900);
PAINT GREEN (-6100 900);
DISPLAY INVISIBLE (-6100 900);
FORCEPROP 1 LAST COMMENT_BODY TRUE
J 0
(-6325 950);
DISPLAY 1.170213 (-6325 950);
PAINT GREEN (-6325 950);
DISPLAY INVISIBLE (-6325 950);
FORCEPROP 2 LAST PATH I3
J 0
(-6375 1100);
DISPLAY 1.021277 (-6375 1100);
PAINT ORANGE (-6375 1100);
DISPLAY INVISIBLE (-6375 1100);
FORCEADD TAP..6
(-5575 1975);
FORCEPROP 3 LASTPIN (-5525 1975) SIG_NAME M_K_DQ<9>
J 0
(-5515 1985);
DISPLAY 0.659574 (-5515 1985);
PAINT MONO (-5515 1985);
DISPLAY INVISIBLE (-5515 1985);
FORCEPROP 1 LASTPIN (-5525 1975) BN 9
J 0
(-5577 1983);
DISPLAY 0.617021 (-5577 1983);
PAINT GREEN (-5577 1983);
FORCEPROP 2 LAST CDS_LIB mstr_standard
J 0
(-5575 1975);
PAINT MONO (-5575 1975);
DISPLAY INVISIBLE (-5575 1975);
FORCEPROP 1 LAST BODY_TYPE PLUMBING
J 0
(-5575 1925);
DISPLAY 1.595745 (-5575 1925);
PAINT GREEN (-5575 1925);
DISPLAY INVISIBLE (-5575 1925);
FORCEPROP 1 LAST HDL_TAP TRUE
J 0
(-5250 1850);
DISPLAY 1.595745 (-5250 1850);
PAINT GREEN (-5250 1850);
DISPLAY INVISIBLE (-5250 1850);
FORCEPROP 1 LAST PATH I31
J 0
(-5577 1975);
DISPLAY 0.872340 (-5577 1975);
PAINT GREEN (-5577 1975);
DISPLAY INVISIBLE (-5577 1975);
FORCEADD TAP..6
(-5575 2025);
FORCEPROP 3 LASTPIN (-5525 2025) SIG_NAME M_K_DQ<10>
J 0
(-5515 2035);
DISPLAY 0.659574 (-5515 2035);
PAINT MONO (-5515 2035);
DISPLAY INVISIBLE (-5515 2035);
FORCEPROP 1 LASTPIN (-5525 2025) BN 10
J 0
(-5577 2033);
DISPLAY 0.617021 (-5577 2033);
PAINT GREEN (-5577 2033);
FORCEPROP 2 LAST CDS_LIB mstr_standard
J 0
(-5575 2025);
PAINT MONO (-5575 2025);
DISPLAY INVISIBLE (-5575 2025);
FORCEPROP 1 LAST BODY_TYPE PLUMBING
J 0
(-5575 1975);
DISPLAY 1.595745 (-5575 1975);
PAINT GREEN (-5575 1975);
DISPLAY INVISIBLE (-5575 1975);
FORCEPROP 1 LAST HDL_TAP TRUE
J 0
(-5250 1900);
DISPLAY 1.595745 (-5250 1900);
PAINT GREEN (-5250 1900);
DISPLAY INVISIBLE (-5250 1900);
FORCEPROP 1 LAST PATH I32
J 0
(-5577 2025);
DISPLAY 0.872340 (-5577 2025);
PAINT GREEN (-5577 2025);
DISPLAY INVISIBLE (-5577 2025);
FORCEADD TAP..6
(-5575 2075);
FORCEPROP 3 LASTPIN (-5525 2075) SIG_NAME M_K_DQ<11>
J 0
(-5515 2085);
DISPLAY 0.659574 (-5515 2085);
PAINT MONO (-5515 2085);
DISPLAY INVISIBLE (-5515 2085);
FORCEPROP 1 LASTPIN (-5525 2075) BN 11
J 0
(-5577 2083);
DISPLAY 0.617021 (-5577 2083);
PAINT GREEN (-5577 2083);
FORCEPROP 2 LAST CDS_LIB mstr_standard
J 0
(-5575 2075);
PAINT MONO (-5575 2075);
DISPLAY INVISIBLE (-5575 2075);
FORCEPROP 1 LAST BODY_TYPE PLUMBING
J 0
(-5575 2025);
DISPLAY 1.595745 (-5575 2025);
PAINT GREEN (-5575 2025);
DISPLAY INVISIBLE (-5575 2025);
FORCEPROP 1 LAST HDL_TAP TRUE
J 0
(-5250 1950);
DISPLAY 1.595745 (-5250 1950);
PAINT GREEN (-5250 1950);
DISPLAY INVISIBLE (-5250 1950);
FORCEPROP 1 LAST PATH I33
J 0
(-5577 2075);
DISPLAY 0.872340 (-5577 2075);
PAINT GREEN (-5577 2075);
DISPLAY INVISIBLE (-5577 2075);
FORCEADD TAP..6
(-5575 2125);
FORCEPROP 3 LASTPIN (-5525 2125) SIG_NAME M_K_DQ<12>
J 0
(-5515 2135);
DISPLAY 0.659574 (-5515 2135);
PAINT MONO (-5515 2135);
DISPLAY INVISIBLE (-5515 2135);
FORCEPROP 1 LASTPIN (-5525 2125) BN 12
J 0
(-5577 2133);
DISPLAY 0.617021 (-5577 2133);
PAINT GREEN (-5577 2133);
FORCEPROP 2 LAST CDS_LIB mstr_standard
J 0
(-5575 2125);
PAINT MONO (-5575 2125);
DISPLAY INVISIBLE (-5575 2125);
FORCEPROP 1 LAST BODY_TYPE PLUMBING
J 0
(-5575 2075);
DISPLAY 1.595745 (-5575 2075);
PAINT GREEN (-5575 2075);
DISPLAY INVISIBLE (-5575 2075);
FORCEPROP 1 LAST HDL_TAP TRUE
J 0
(-5250 2000);
DISPLAY 1.595745 (-5250 2000);
PAINT GREEN (-5250 2000);
DISPLAY INVISIBLE (-5250 2000);
FORCEPROP 1 LAST PATH I34
J 0
(-5577 2125);
DISPLAY 0.872340 (-5577 2125);
PAINT GREEN (-5577 2125);
DISPLAY INVISIBLE (-5577 2125);
FORCEADD TAP..6
(-5575 2175);
FORCEPROP 3 LASTPIN (-5525 2175) SIG_NAME M_K_DQ<13>
J 0
(-5515 2185);
DISPLAY 0.659574 (-5515 2185);
PAINT MONO (-5515 2185);
DISPLAY INVISIBLE (-5515 2185);
FORCEPROP 1 LASTPIN (-5525 2175) BN 13
J 0
(-5577 2183);
DISPLAY 0.617021 (-5577 2183);
PAINT GREEN (-5577 2183);
FORCEPROP 2 LAST CDS_LIB mstr_standard
J 0
(-5575 2175);
PAINT MONO (-5575 2175);
DISPLAY INVISIBLE (-5575 2175);
FORCEPROP 1 LAST BODY_TYPE PLUMBING
J 0
(-5575 2125);
DISPLAY 1.595745 (-5575 2125);
PAINT GREEN (-5575 2125);
DISPLAY INVISIBLE (-5575 2125);
FORCEPROP 1 LAST HDL_TAP TRUE
J 0
(-5250 2050);
DISPLAY 1.595745 (-5250 2050);
PAINT GREEN (-5250 2050);
DISPLAY INVISIBLE (-5250 2050);
FORCEPROP 1 LAST PATH I35
J 0
(-5577 2175);
DISPLAY 0.872340 (-5577 2175);
PAINT GREEN (-5577 2175);
DISPLAY INVISIBLE (-5577 2175);
FORCEADD TAP..6
(-5575 2225);
FORCEPROP 3 LASTPIN (-5525 2225) SIG_NAME M_K_DQ<14>
J 0
(-5515 2235);
DISPLAY 0.659574 (-5515 2235);
PAINT MONO (-5515 2235);
DISPLAY INVISIBLE (-5515 2235);
FORCEPROP 1 LASTPIN (-5525 2225) BN 14
J 0
(-5577 2233);
DISPLAY 0.617021 (-5577 2233);
PAINT GREEN (-5577 2233);
FORCEPROP 2 LAST CDS_LIB mstr_standard
J 0
(-5575 2225);
PAINT MONO (-5575 2225);
DISPLAY INVISIBLE (-5575 2225);
FORCEPROP 1 LAST BODY_TYPE PLUMBING
J 0
(-5575 2175);
DISPLAY 1.595745 (-5575 2175);
PAINT GREEN (-5575 2175);
DISPLAY INVISIBLE (-5575 2175);
FORCEPROP 1 LAST HDL_TAP TRUE
J 0
(-5250 2100);
DISPLAY 1.595745 (-5250 2100);
PAINT GREEN (-5250 2100);
DISPLAY INVISIBLE (-5250 2100);
FORCEPROP 1 LAST PATH I36
J 0
(-5577 2225);
DISPLAY 0.872340 (-5577 2225);
PAINT GREEN (-5577 2225);
DISPLAY INVISIBLE (-5577 2225);
FORCEADD TAP..6
(-5575 2275);
FORCEPROP 3 LASTPIN (-5525 2275) SIG_NAME M_K_DQ<15>
J 0
(-5515 2285);
DISPLAY 0.659574 (-5515 2285);
PAINT MONO (-5515 2285);
DISPLAY INVISIBLE (-5515 2285);
FORCEPROP 1 LASTPIN (-5525 2275) BN 15
J 0
(-5577 2283);
DISPLAY 0.617021 (-5577 2283);
PAINT GREEN (-5577 2283);
FORCEPROP 2 LAST CDS_LIB mstr_standard
J 0
(-5575 2275);
PAINT MONO (-5575 2275);
DISPLAY INVISIBLE (-5575 2275);
FORCEPROP 1 LAST BODY_TYPE PLUMBING
J 0
(-5575 2225);
DISPLAY 1.595745 (-5575 2225);
PAINT GREEN (-5575 2225);
DISPLAY INVISIBLE (-5575 2225);
FORCEPROP 1 LAST HDL_TAP TRUE
J 0
(-5250 2150);
DISPLAY 1.595745 (-5250 2150);
PAINT GREEN (-5250 2150);
DISPLAY INVISIBLE (-5250 2150);
FORCEPROP 1 LAST PATH I37
J 0
(-5577 2275);
DISPLAY 0.872340 (-5577 2275);
PAINT GREEN (-5577 2275);
DISPLAY INVISIBLE (-5577 2275);
FORCEADD TAP..6
(-5575 2325);
FORCEPROP 3 LASTPIN (-5525 2325) SIG_NAME M_K_DQ<16>
J 0
(-5515 2335);
DISPLAY 0.659574 (-5515 2335);
PAINT MONO (-5515 2335);
DISPLAY INVISIBLE (-5515 2335);
FORCEPROP 1 LASTPIN (-5525 2325) BN 16
J 0
(-5577 2333);
DISPLAY 0.617021 (-5577 2333);
PAINT GREEN (-5577 2333);
FORCEPROP 2 LAST CDS_LIB mstr_standard
J 0
(-5575 2325);
PAINT MONO (-5575 2325);
DISPLAY INVISIBLE (-5575 2325);
FORCEPROP 1 LAST BODY_TYPE PLUMBING
J 0
(-5575 2275);
DISPLAY 1.595745 (-5575 2275);
PAINT GREEN (-5575 2275);
DISPLAY INVISIBLE (-5575 2275);
FORCEPROP 1 LAST HDL_TAP TRUE
J 0
(-5250 2200);
DISPLAY 1.595745 (-5250 2200);
PAINT GREEN (-5250 2200);
DISPLAY INVISIBLE (-5250 2200);
FORCEPROP 1 LAST PATH I38
J 0
(-5577 2325);
DISPLAY 0.872340 (-5577 2325);
PAINT GREEN (-5577 2325);
DISPLAY INVISIBLE (-5577 2325);
FORCEADD TAP..6
(-5575 2375);
FORCEPROP 3 LASTPIN (-5525 2375) SIG_NAME M_K_DQ<17>
J 0
(-5515 2385);
DISPLAY 0.659574 (-5515 2385);
PAINT MONO (-5515 2385);
DISPLAY INVISIBLE (-5515 2385);
FORCEPROP 1 LASTPIN (-5525 2375) BN 17
J 0
(-5577 2383);
DISPLAY 0.617021 (-5577 2383);
PAINT GREEN (-5577 2383);
FORCEPROP 2 LAST CDS_LIB mstr_standard
J 0
(-5575 2375);
PAINT MONO (-5575 2375);
DISPLAY INVISIBLE (-5575 2375);
FORCEPROP 1 LAST BODY_TYPE PLUMBING
J 0
(-5575 2325);
DISPLAY 1.595745 (-5575 2325);
PAINT GREEN (-5575 2325);
DISPLAY INVISIBLE (-5575 2325);
FORCEPROP 1 LAST HDL_TAP TRUE
J 0
(-5250 2250);
DISPLAY 1.595745 (-5250 2250);
PAINT GREEN (-5250 2250);
DISPLAY INVISIBLE (-5250 2250);
FORCEPROP 1 LAST PATH I39
J 0
(-5577 2375);
DISPLAY 0.872340 (-5577 2375);
PAINT GREEN (-5577 2375);
DISPLAY INVISIBLE (-5577 2375);
FORCEADD OFFPAGE..6
(-6425 1475);
FORCEPROP 2 LAST $XR1 84 
J 0
(-6764 1475);
DISPLAY 0.638298 (-6764 1475);
PAINT MONO (-6764 1475);
FORCEPROP 2 LAST $XR0 83 
J 0
(-6674 1475);
DISPLAY 0.638298 (-6674 1475);
PAINT MONO (-6674 1475);
FORCEPROP 2 LAST CDS_LIB mstr_standard
J 0
(-6425 1475);
PAINT MONO (-6425 1475);
DISPLAY INVISIBLE (-6425 1475);
FORCEPROP 1 LAST OFFPAGE TRUE
J 0
(-6100 1350);
DISPLAY 1.170213 (-6100 1350);
PAINT GREEN (-6100 1350);
DISPLAY INVISIBLE (-6100 1350);
FORCEPROP 1 LAST COMMENT_BODY TRUE
J 0
(-6325 1400);
DISPLAY 1.170213 (-6325 1400);
PAINT GREEN (-6325 1400);
DISPLAY INVISIBLE (-6325 1400);
FORCEPROP 2 LAST PATH I4
J 0
(-6375 1550);
DISPLAY 1.021277 (-6375 1550);
PAINT ORANGE (-6375 1550);
DISPLAY INVISIBLE (-6375 1550);
FORCEADD TAP..6
(-5575 2425);
FORCEPROP 3 LASTPIN (-5525 2425) SIG_NAME M_K_DQ<18>
J 0
(-5515 2435);
DISPLAY 0.659574 (-5515 2435);
PAINT MONO (-5515 2435);
DISPLAY INVISIBLE (-5515 2435);
FORCEPROP 1 LASTPIN (-5525 2425) BN 18
J 0
(-5577 2433);
DISPLAY 0.617021 (-5577 2433);
PAINT GREEN (-5577 2433);
FORCEPROP 2 LAST CDS_LIB mstr_standard
J 0
(-5575 2425);
PAINT MONO (-5575 2425);
DISPLAY INVISIBLE (-5575 2425);
FORCEPROP 1 LAST BODY_TYPE PLUMBING
J 0
(-5575 2375);
DISPLAY 1.595745 (-5575 2375);
PAINT GREEN (-5575 2375);
DISPLAY INVISIBLE (-5575 2375);
FORCEPROP 1 LAST HDL_TAP TRUE
J 0
(-5250 2300);
DISPLAY 1.595745 (-5250 2300);
PAINT GREEN (-5250 2300);
DISPLAY INVISIBLE (-5250 2300);
FORCEPROP 1 LAST PATH I40
J 0
(-5577 2425);
DISPLAY 0.872340 (-5577 2425);
PAINT GREEN (-5577 2425);
DISPLAY INVISIBLE (-5577 2425);
FORCEADD TAP..6
(-5575 2475);
FORCEPROP 3 LASTPIN (-5525 2475) SIG_NAME M_K_DQ<19>
J 0
(-5515 2485);
DISPLAY 0.659574 (-5515 2485);
PAINT MONO (-5515 2485);
DISPLAY INVISIBLE (-5515 2485);
FORCEPROP 1 LASTPIN (-5525 2475) BN 19
J 0
(-5577 2483);
DISPLAY 0.617021 (-5577 2483);
PAINT GREEN (-5577 2483);
FORCEPROP 2 LAST CDS_LIB mstr_standard
J 0
(-5575 2475);
PAINT MONO (-5575 2475);
DISPLAY INVISIBLE (-5575 2475);
FORCEPROP 1 LAST BODY_TYPE PLUMBING
J 0
(-5575 2425);
DISPLAY 1.595745 (-5575 2425);
PAINT GREEN (-5575 2425);
DISPLAY INVISIBLE (-5575 2425);
FORCEPROP 1 LAST HDL_TAP TRUE
J 0
(-5250 2350);
DISPLAY 1.595745 (-5250 2350);
PAINT GREEN (-5250 2350);
DISPLAY INVISIBLE (-5250 2350);
FORCEPROP 1 LAST PATH I41
J 0
(-5577 2475);
DISPLAY 0.872340 (-5577 2475);
PAINT GREEN (-5577 2475);
DISPLAY INVISIBLE (-5577 2475);
FORCEADD TAP..6
(-5575 2525);
FORCEPROP 3 LASTPIN (-5525 2525) SIG_NAME M_K_DQ<20>
J 0
(-5515 2535);
DISPLAY 0.659574 (-5515 2535);
PAINT MONO (-5515 2535);
DISPLAY INVISIBLE (-5515 2535);
FORCEPROP 1 LASTPIN (-5525 2525) BN 20
J 0
(-5577 2533);
DISPLAY 0.617021 (-5577 2533);
PAINT GREEN (-5577 2533);
FORCEPROP 2 LAST CDS_LIB mstr_standard
J 0
(-5575 2525);
PAINT MONO (-5575 2525);
DISPLAY INVISIBLE (-5575 2525);
FORCEPROP 1 LAST BODY_TYPE PLUMBING
J 0
(-5575 2475);
DISPLAY 1.595745 (-5575 2475);
PAINT GREEN (-5575 2475);
DISPLAY INVISIBLE (-5575 2475);
FORCEPROP 1 LAST HDL_TAP TRUE
J 0
(-5250 2400);
DISPLAY 1.595745 (-5250 2400);
PAINT GREEN (-5250 2400);
DISPLAY INVISIBLE (-5250 2400);
FORCEPROP 1 LAST PATH I42
J 0
(-5577 2525);
DISPLAY 0.872340 (-5577 2525);
PAINT GREEN (-5577 2525);
DISPLAY INVISIBLE (-5577 2525);
FORCEADD TAP..6
(-5575 2575);
FORCEPROP 3 LASTPIN (-5525 2575) SIG_NAME M_K_DQ<21>
J 0
(-5515 2585);
DISPLAY 0.659574 (-5515 2585);
PAINT MONO (-5515 2585);
DISPLAY INVISIBLE (-5515 2585);
FORCEPROP 1 LASTPIN (-5525 2575) BN 21
J 0
(-5577 2583);
DISPLAY 0.617021 (-5577 2583);
PAINT GREEN (-5577 2583);
FORCEPROP 2 LAST CDS_LIB mstr_standard
J 0
(-5575 2575);
PAINT MONO (-5575 2575);
DISPLAY INVISIBLE (-5575 2575);
FORCEPROP 1 LAST BODY_TYPE PLUMBING
J 0
(-5575 2525);
DISPLAY 1.595745 (-5575 2525);
PAINT GREEN (-5575 2525);
DISPLAY INVISIBLE (-5575 2525);
FORCEPROP 1 LAST HDL_TAP TRUE
J 0
(-5250 2450);
DISPLAY 1.595745 (-5250 2450);
PAINT GREEN (-5250 2450);
DISPLAY INVISIBLE (-5250 2450);
FORCEPROP 1 LAST PATH I43
J 0
(-5577 2575);
DISPLAY 0.872340 (-5577 2575);
PAINT GREEN (-5577 2575);
DISPLAY INVISIBLE (-5577 2575);
FORCEADD TAP..6
(-5575 2625);
FORCEPROP 3 LASTPIN (-5525 2625) SIG_NAME M_K_DQ<22>
J 0
(-5515 2635);
DISPLAY 0.659574 (-5515 2635);
PAINT MONO (-5515 2635);
DISPLAY INVISIBLE (-5515 2635);
FORCEPROP 1 LASTPIN (-5525 2625) BN 22
J 0
(-5577 2633);
DISPLAY 0.617021 (-5577 2633);
PAINT GREEN (-5577 2633);
FORCEPROP 2 LAST CDS_LIB mstr_standard
J 0
(-5575 2625);
PAINT MONO (-5575 2625);
DISPLAY INVISIBLE (-5575 2625);
FORCEPROP 1 LAST BODY_TYPE PLUMBING
J 0
(-5575 2575);
DISPLAY 1.595745 (-5575 2575);
PAINT GREEN (-5575 2575);
DISPLAY INVISIBLE (-5575 2575);
FORCEPROP 1 LAST HDL_TAP TRUE
J 0
(-5250 2500);
DISPLAY 1.595745 (-5250 2500);
PAINT GREEN (-5250 2500);
DISPLAY INVISIBLE (-5250 2500);
FORCEPROP 1 LAST PATH I44
J 0
(-5577 2625);
DISPLAY 0.872340 (-5577 2625);
PAINT GREEN (-5577 2625);
DISPLAY INVISIBLE (-5577 2625);
FORCEADD TAP..6
(-5575 2675);
FORCEPROP 3 LASTPIN (-5525 2675) SIG_NAME M_K_DQ<23>
J 0
(-5515 2685);
DISPLAY 0.659574 (-5515 2685);
PAINT MONO (-5515 2685);
DISPLAY INVISIBLE (-5515 2685);
FORCEPROP 1 LASTPIN (-5525 2675) BN 23
J 0
(-5577 2683);
DISPLAY 0.617021 (-5577 2683);
PAINT GREEN (-5577 2683);
FORCEPROP 2 LAST CDS_LIB mstr_standard
J 0
(-5575 2675);
PAINT MONO (-5575 2675);
DISPLAY INVISIBLE (-5575 2675);
FORCEPROP 1 LAST BODY_TYPE PLUMBING
J 0
(-5575 2625);
DISPLAY 1.595745 (-5575 2625);
PAINT GREEN (-5575 2625);
DISPLAY INVISIBLE (-5575 2625);
FORCEPROP 1 LAST HDL_TAP TRUE
J 0
(-5250 2550);
DISPLAY 1.595745 (-5250 2550);
PAINT GREEN (-5250 2550);
DISPLAY INVISIBLE (-5250 2550);
FORCEPROP 1 LAST PATH I45
J 0
(-5577 2675);
DISPLAY 0.872340 (-5577 2675);
PAINT GREEN (-5577 2675);
DISPLAY INVISIBLE (-5577 2675);
FORCEADD TAP..6
(-5575 2725);
FORCEPROP 3 LASTPIN (-5525 2725) SIG_NAME M_K_DQ<24>
J 0
(-5515 2735);
DISPLAY 0.659574 (-5515 2735);
PAINT MONO (-5515 2735);
DISPLAY INVISIBLE (-5515 2735);
FORCEPROP 1 LASTPIN (-5525 2725) BN 24
J 0
(-5577 2733);
DISPLAY 0.617021 (-5577 2733);
PAINT GREEN (-5577 2733);
FORCEPROP 2 LAST CDS_LIB mstr_standard
J 0
(-5575 2725);
PAINT MONO (-5575 2725);
DISPLAY INVISIBLE (-5575 2725);
FORCEPROP 1 LAST BODY_TYPE PLUMBING
J 0
(-5575 2675);
DISPLAY 1.595745 (-5575 2675);
PAINT GREEN (-5575 2675);
DISPLAY INVISIBLE (-5575 2675);
FORCEPROP 1 LAST HDL_TAP TRUE
J 0
(-5250 2600);
DISPLAY 1.595745 (-5250 2600);
PAINT GREEN (-5250 2600);
DISPLAY INVISIBLE (-5250 2600);
FORCEPROP 1 LAST PATH I46
J 0
(-5577 2725);
DISPLAY 0.872340 (-5577 2725);
PAINT GREEN (-5577 2725);
DISPLAY INVISIBLE (-5577 2725);
FORCEADD TAP..6
(-5575 2825);
FORCEPROP 3 LASTPIN (-5525 2825) SIG_NAME M_K_DQ<26>
J 0
(-5515 2835);
DISPLAY 0.659574 (-5515 2835);
PAINT MONO (-5515 2835);
DISPLAY INVISIBLE (-5515 2835);
FORCEPROP 1 LASTPIN (-5525 2825) BN 26
J 0
(-5577 2833);
DISPLAY 0.617021 (-5577 2833);
PAINT GREEN (-5577 2833);
FORCEPROP 2 LAST CDS_LIB mstr_standard
J 0
(-5575 2825);
PAINT MONO (-5575 2825);
DISPLAY INVISIBLE (-5575 2825);
FORCEPROP 1 LAST BODY_TYPE PLUMBING
J 0
(-5575 2775);
DISPLAY 1.595745 (-5575 2775);
PAINT GREEN (-5575 2775);
DISPLAY INVISIBLE (-5575 2775);
FORCEPROP 1 LAST HDL_TAP TRUE
J 0
(-5250 2700);
DISPLAY 1.595745 (-5250 2700);
PAINT GREEN (-5250 2700);
DISPLAY INVISIBLE (-5250 2700);
FORCEPROP 1 LAST PATH I47
J 0
(-5577 2825);
DISPLAY 0.872340 (-5577 2825);
PAINT GREEN (-5577 2825);
DISPLAY INVISIBLE (-5577 2825);
FORCEADD TAP..6
(-5575 2775);
FORCEPROP 3 LASTPIN (-5525 2775) SIG_NAME M_K_DQ<25>
J 0
(-5515 2785);
DISPLAY 0.659574 (-5515 2785);
PAINT MONO (-5515 2785);
DISPLAY INVISIBLE (-5515 2785);
FORCEPROP 1 LASTPIN (-5525 2775) BN 25
J 0
(-5577 2783);
DISPLAY 0.617021 (-5577 2783);
PAINT GREEN (-5577 2783);
FORCEPROP 2 LAST CDS_LIB mstr_standard
J 0
(-5575 2775);
PAINT MONO (-5575 2775);
DISPLAY INVISIBLE (-5575 2775);
FORCEPROP 1 LAST BODY_TYPE PLUMBING
J 0
(-5575 2725);
DISPLAY 1.595745 (-5575 2725);
PAINT GREEN (-5575 2725);
DISPLAY INVISIBLE (-5575 2725);
FORCEPROP 1 LAST HDL_TAP TRUE
J 0
(-5250 2650);
DISPLAY 1.595745 (-5250 2650);
PAINT GREEN (-5250 2650);
DISPLAY INVISIBLE (-5250 2650);
FORCEPROP 1 LAST PATH I48
J 0
(-5577 2775);
DISPLAY 0.872340 (-5577 2775);
PAINT GREEN (-5577 2775);
DISPLAY INVISIBLE (-5577 2775);
FORCEADD TAP..6
(-5575 2875);
FORCEPROP 3 LASTPIN (-5525 2875) SIG_NAME M_K_DQ<27>
J 0
(-5515 2885);
DISPLAY 0.659574 (-5515 2885);
PAINT MONO (-5515 2885);
DISPLAY INVISIBLE (-5515 2885);
FORCEPROP 1 LASTPIN (-5525 2875) BN 27
J 0
(-5577 2883);
DISPLAY 0.617021 (-5577 2883);
PAINT GREEN (-5577 2883);
FORCEPROP 2 LAST CDS_LIB mstr_standard
J 0
(-5575 2875);
PAINT MONO (-5575 2875);
DISPLAY INVISIBLE (-5575 2875);
FORCEPROP 1 LAST BODY_TYPE PLUMBING
J 0
(-5575 2825);
DISPLAY 1.595745 (-5575 2825);
PAINT GREEN (-5575 2825);
DISPLAY INVISIBLE (-5575 2825);
FORCEPROP 1 LAST HDL_TAP TRUE
J 0
(-5250 2750);
DISPLAY 1.595745 (-5250 2750);
PAINT GREEN (-5250 2750);
DISPLAY INVISIBLE (-5250 2750);
FORCEPROP 1 LAST PATH I49
J 0
(-5577 2875);
DISPLAY 0.872340 (-5577 2875);
PAINT GREEN (-5577 2875);
DISPLAY INVISIBLE (-5577 2875);
FORCEADD TAP..6
(-5575 625);
FORCEPROP 3 LASTPIN (-5525 625) SIG_NAME M_K_CLK_DN<0>
J 0
(-5515 635);
DISPLAY 0.659574 (-5515 635);
PAINT MONO (-5515 635);
DISPLAY INVISIBLE (-5515 635);
FORCEPROP 1 LASTPIN (-5525 625) BN 0
J 0
(-5577 633);
DISPLAY 0.617021 (-5577 633);
PAINT GREEN (-5577 633);
FORCEPROP 2 LAST CDS_LIB mstr_standard
J 0
(-5575 625);
PAINT MONO (-5575 625);
DISPLAY INVISIBLE (-5575 625);
FORCEPROP 1 LAST BODY_TYPE PLUMBING
J 0
(-5575 575);
DISPLAY 1.595745 (-5575 575);
PAINT GREEN (-5575 575);
DISPLAY INVISIBLE (-5575 575);
FORCEPROP 1 LAST HDL_TAP TRUE
J 0
(-5250 500);
DISPLAY 1.595745 (-5250 500);
PAINT GREEN (-5250 500);
DISPLAY INVISIBLE (-5250 500);
FORCEPROP 1 LAST PATH I5
J 0
(-5577 625);
DISPLAY 0.872340 (-5577 625);
PAINT GREEN (-5577 625);
DISPLAY INVISIBLE (-5577 625);
FORCEADD TAP..6
(-5575 2925);
FORCEPROP 3 LASTPIN (-5525 2925) SIG_NAME M_K_DQ<28>
J 0
(-5515 2935);
DISPLAY 0.659574 (-5515 2935);
PAINT MONO (-5515 2935);
DISPLAY INVISIBLE (-5515 2935);
FORCEPROP 1 LASTPIN (-5525 2925) BN 28
J 0
(-5577 2933);
DISPLAY 0.617021 (-5577 2933);
PAINT GREEN (-5577 2933);
FORCEPROP 2 LAST CDS_LIB mstr_standard
J 0
(-5575 2925);
PAINT MONO (-5575 2925);
DISPLAY INVISIBLE (-5575 2925);
FORCEPROP 1 LAST BODY_TYPE PLUMBING
J 0
(-5575 2875);
DISPLAY 1.595745 (-5575 2875);
PAINT GREEN (-5575 2875);
DISPLAY INVISIBLE (-5575 2875);
FORCEPROP 1 LAST HDL_TAP TRUE
J 0
(-5250 2800);
DISPLAY 1.595745 (-5250 2800);
PAINT GREEN (-5250 2800);
DISPLAY INVISIBLE (-5250 2800);
FORCEPROP 1 LAST PATH I50
J 0
(-5577 2925);
DISPLAY 0.872340 (-5577 2925);
PAINT GREEN (-5577 2925);
DISPLAY INVISIBLE (-5577 2925);
FORCEADD TAP..6
(-5575 2975);
FORCEPROP 3 LASTPIN (-5525 2975) SIG_NAME M_K_DQ<29>
J 0
(-5515 2985);
DISPLAY 0.659574 (-5515 2985);
PAINT MONO (-5515 2985);
DISPLAY INVISIBLE (-5515 2985);
FORCEPROP 1 LASTPIN (-5525 2975) BN 29
J 0
(-5577 2983);
DISPLAY 0.617021 (-5577 2983);
PAINT GREEN (-5577 2983);
FORCEPROP 2 LAST CDS_LIB mstr_standard
J 0
(-5575 2975);
PAINT MONO (-5575 2975);
DISPLAY INVISIBLE (-5575 2975);
FORCEPROP 1 LAST BODY_TYPE PLUMBING
J 0
(-5575 2925);
DISPLAY 1.595745 (-5575 2925);
PAINT GREEN (-5575 2925);
DISPLAY INVISIBLE (-5575 2925);
FORCEPROP 1 LAST HDL_TAP TRUE
J 0
(-5250 2850);
DISPLAY 1.595745 (-5250 2850);
PAINT GREEN (-5250 2850);
DISPLAY INVISIBLE (-5250 2850);
FORCEPROP 1 LAST PATH I51
J 0
(-5577 2975);
DISPLAY 0.872340 (-5577 2975);
PAINT GREEN (-5577 2975);
DISPLAY INVISIBLE (-5577 2975);
FORCEADD TAP..6
(-5575 3075);
FORCEPROP 3 LASTPIN (-5525 3075) SIG_NAME M_K_DQ<31>
J 0
(-5515 3085);
DISPLAY 0.659574 (-5515 3085);
PAINT MONO (-5515 3085);
DISPLAY INVISIBLE (-5515 3085);
FORCEPROP 1 LASTPIN (-5525 3075) BN 31
J 0
(-5577 3083);
DISPLAY 0.617021 (-5577 3083);
PAINT GREEN (-5577 3083);
FORCEPROP 2 LAST CDS_LIB mstr_standard
J 0
(-5575 3075);
PAINT MONO (-5575 3075);
DISPLAY INVISIBLE (-5575 3075);
FORCEPROP 1 LAST BODY_TYPE PLUMBING
J 0
(-5575 3025);
DISPLAY 1.595745 (-5575 3025);
PAINT GREEN (-5575 3025);
DISPLAY INVISIBLE (-5575 3025);
FORCEPROP 1 LAST HDL_TAP TRUE
J 0
(-5250 2950);
DISPLAY 1.595745 (-5250 2950);
PAINT GREEN (-5250 2950);
DISPLAY INVISIBLE (-5250 2950);
FORCEPROP 1 LAST PATH I52
J 0
(-5577 3075);
DISPLAY 0.872340 (-5577 3075);
PAINT GREEN (-5577 3075);
DISPLAY INVISIBLE (-5577 3075);
FORCEADD TAP..6
(-5575 3025);
FORCEPROP 3 LASTPIN (-5525 3025) SIG_NAME M_K_DQ<30>
J 0
(-5515 3035);
DISPLAY 0.659574 (-5515 3035);
PAINT MONO (-5515 3035);
DISPLAY INVISIBLE (-5515 3035);
FORCEPROP 1 LASTPIN (-5525 3025) BN 30
J 0
(-5577 3033);
DISPLAY 0.617021 (-5577 3033);
PAINT GREEN (-5577 3033);
FORCEPROP 2 LAST CDS_LIB mstr_standard
J 0
(-5575 3025);
PAINT MONO (-5575 3025);
DISPLAY INVISIBLE (-5575 3025);
FORCEPROP 1 LAST BODY_TYPE PLUMBING
J 0
(-5575 2975);
DISPLAY 1.595745 (-5575 2975);
PAINT GREEN (-5575 2975);
DISPLAY INVISIBLE (-5575 2975);
FORCEPROP 1 LAST HDL_TAP TRUE
J 0
(-5250 2900);
DISPLAY 1.595745 (-5250 2900);
PAINT GREEN (-5250 2900);
DISPLAY INVISIBLE (-5250 2900);
FORCEPROP 1 LAST PATH I53
J 0
(-5577 3025);
DISPLAY 0.872340 (-5577 3025);
PAINT GREEN (-5577 3025);
DISPLAY INVISIBLE (-5577 3025);
FORCEADD TAP..6
(-5575 3125);
FORCEPROP 3 LASTPIN (-5525 3125) SIG_NAME M_K_DQ<32>
J 0
(-5515 3135);
DISPLAY 0.659574 (-5515 3135);
PAINT MONO (-5515 3135);
DISPLAY INVISIBLE (-5515 3135);
FORCEPROP 1 LASTPIN (-5525 3125) BN 32
J 0
(-5577 3133);
DISPLAY 0.617021 (-5577 3133);
PAINT GREEN (-5577 3133);
FORCEPROP 2 LAST CDS_LIB mstr_standard
J 0
(-5575 3125);
PAINT MONO (-5575 3125);
DISPLAY INVISIBLE (-5575 3125);
FORCEPROP 1 LAST BODY_TYPE PLUMBING
J 0
(-5575 3075);
DISPLAY 1.595745 (-5575 3075);
PAINT GREEN (-5575 3075);
DISPLAY INVISIBLE (-5575 3075);
FORCEPROP 1 LAST HDL_TAP TRUE
J 0
(-5250 3000);
DISPLAY 1.595745 (-5250 3000);
PAINT GREEN (-5250 3000);
DISPLAY INVISIBLE (-5250 3000);
FORCEPROP 1 LAST PATH I54
J 0
(-5577 3125);
DISPLAY 0.872340 (-5577 3125);
PAINT GREEN (-5577 3125);
DISPLAY INVISIBLE (-5577 3125);
FORCEADD TAP..6
(-5575 3175);
FORCEPROP 3 LASTPIN (-5525 3175) SIG_NAME M_K_DQ<33>
J 0
(-5515 3185);
DISPLAY 0.659574 (-5515 3185);
PAINT MONO (-5515 3185);
DISPLAY INVISIBLE (-5515 3185);
FORCEPROP 1 LASTPIN (-5525 3175) BN 33
J 0
(-5577 3183);
DISPLAY 0.617021 (-5577 3183);
PAINT GREEN (-5577 3183);
FORCEPROP 2 LAST CDS_LIB mstr_standard
J 0
(-5575 3175);
PAINT MONO (-5575 3175);
DISPLAY INVISIBLE (-5575 3175);
FORCEPROP 1 LAST BODY_TYPE PLUMBING
J 0
(-5575 3125);
DISPLAY 1.595745 (-5575 3125);
PAINT GREEN (-5575 3125);
DISPLAY INVISIBLE (-5575 3125);
FORCEPROP 1 LAST HDL_TAP TRUE
J 0
(-5250 3050);
DISPLAY 1.595745 (-5250 3050);
PAINT GREEN (-5250 3050);
DISPLAY INVISIBLE (-5250 3050);
FORCEPROP 1 LAST PATH I55
J 0
(-5577 3175);
DISPLAY 0.872340 (-5577 3175);
PAINT GREEN (-5577 3175);
DISPLAY INVISIBLE (-5577 3175);
FORCEADD TAP..6
(-5575 3225);
FORCEPROP 3 LASTPIN (-5525 3225) SIG_NAME M_K_DQ<34>
J 0
(-5515 3235);
DISPLAY 0.659574 (-5515 3235);
PAINT MONO (-5515 3235);
DISPLAY INVISIBLE (-5515 3235);
FORCEPROP 1 LASTPIN (-5525 3225) BN 34
J 0
(-5577 3233);
DISPLAY 0.617021 (-5577 3233);
PAINT GREEN (-5577 3233);
FORCEPROP 2 LAST CDS_LIB mstr_standard
J 0
(-5575 3225);
PAINT MONO (-5575 3225);
DISPLAY INVISIBLE (-5575 3225);
FORCEPROP 1 LAST BODY_TYPE PLUMBING
J 0
(-5575 3175);
DISPLAY 1.595745 (-5575 3175);
PAINT GREEN (-5575 3175);
DISPLAY INVISIBLE (-5575 3175);
FORCEPROP 1 LAST HDL_TAP TRUE
J 0
(-5250 3100);
DISPLAY 1.595745 (-5250 3100);
PAINT GREEN (-5250 3100);
DISPLAY INVISIBLE (-5250 3100);
FORCEPROP 1 LAST PATH I56
J 0
(-5577 3225);
DISPLAY 0.872340 (-5577 3225);
PAINT GREEN (-5577 3225);
DISPLAY INVISIBLE (-5577 3225);
FORCEADD TAP..6
(-5575 3325);
FORCEPROP 3 LASTPIN (-5525 3325) SIG_NAME M_K_DQ<36>
J 0
(-5515 3335);
DISPLAY 0.659574 (-5515 3335);
PAINT MONO (-5515 3335);
DISPLAY INVISIBLE (-5515 3335);
FORCEPROP 1 LASTPIN (-5525 3325) BN 36
J 0
(-5577 3333);
DISPLAY 0.617021 (-5577 3333);
PAINT GREEN (-5577 3333);
FORCEPROP 2 LAST CDS_LIB mstr_standard
J 0
(-5575 3325);
PAINT MONO (-5575 3325);
DISPLAY INVISIBLE (-5575 3325);
FORCEPROP 1 LAST BODY_TYPE PLUMBING
J 0
(-5575 3275);
DISPLAY 1.595745 (-5575 3275);
PAINT GREEN (-5575 3275);
DISPLAY INVISIBLE (-5575 3275);
FORCEPROP 1 LAST HDL_TAP TRUE
J 0
(-5250 3200);
DISPLAY 1.595745 (-5250 3200);
PAINT GREEN (-5250 3200);
DISPLAY INVISIBLE (-5250 3200);
FORCEPROP 1 LAST PATH I57
J 0
(-5577 3325);
DISPLAY 0.872340 (-5577 3325);
PAINT GREEN (-5577 3325);
DISPLAY INVISIBLE (-5577 3325);
FORCEADD TAP..6
(-5575 3275);
FORCEPROP 3 LASTPIN (-5525 3275) SIG_NAME M_K_DQ<35>
J 0
(-5515 3285);
DISPLAY 0.659574 (-5515 3285);
PAINT MONO (-5515 3285);
DISPLAY INVISIBLE (-5515 3285);
FORCEPROP 1 LASTPIN (-5525 3275) BN 35
J 0
(-5577 3283);
DISPLAY 0.617021 (-5577 3283);
PAINT GREEN (-5577 3283);
FORCEPROP 2 LAST CDS_LIB mstr_standard
J 0
(-5575 3275);
PAINT MONO (-5575 3275);
DISPLAY INVISIBLE (-5575 3275);
FORCEPROP 1 LAST BODY_TYPE PLUMBING
J 0
(-5575 3225);
DISPLAY 1.595745 (-5575 3225);
PAINT GREEN (-5575 3225);
DISPLAY INVISIBLE (-5575 3225);
FORCEPROP 1 LAST HDL_TAP TRUE
J 0
(-5250 3150);
DISPLAY 1.595745 (-5250 3150);
PAINT GREEN (-5250 3150);
DISPLAY INVISIBLE (-5250 3150);
FORCEPROP 1 LAST PATH I58
J 0
(-5577 3275);
DISPLAY 0.872340 (-5577 3275);
PAINT GREEN (-5577 3275);
DISPLAY INVISIBLE (-5577 3275);
FORCEADD TAP..6
(-5575 3375);
FORCEPROP 3 LASTPIN (-5525 3375) SIG_NAME M_K_DQ<37>
J 0
(-5515 3385);
DISPLAY 0.659574 (-5515 3385);
PAINT MONO (-5515 3385);
DISPLAY INVISIBLE (-5515 3385);
FORCEPROP 1 LASTPIN (-5525 3375) BN 37
J 0
(-5577 3383);
DISPLAY 0.617021 (-5577 3383);
PAINT GREEN (-5577 3383);
FORCEPROP 2 LAST CDS_LIB mstr_standard
J 0
(-5575 3375);
PAINT MONO (-5575 3375);
DISPLAY INVISIBLE (-5575 3375);
FORCEPROP 1 LAST BODY_TYPE PLUMBING
J 0
(-5575 3325);
DISPLAY 1.595745 (-5575 3325);
PAINT GREEN (-5575 3325);
DISPLAY INVISIBLE (-5575 3325);
FORCEPROP 1 LAST HDL_TAP TRUE
J 0
(-5250 3250);
DISPLAY 1.595745 (-5250 3250);
PAINT GREEN (-5250 3250);
DISPLAY INVISIBLE (-5250 3250);
FORCEPROP 1 LAST PATH I59
J 0
(-5577 3375);
DISPLAY 0.872340 (-5577 3375);
PAINT GREEN (-5577 3375);
DISPLAY INVISIBLE (-5577 3375);
FORCEADD TAP..6
(-5575 675);
FORCEPROP 3 LASTPIN (-5525 675) SIG_NAME M_K_CLK_DN<1>
J 0
(-5515 685);
DISPLAY 0.659574 (-5515 685);
PAINT MONO (-5515 685);
DISPLAY INVISIBLE (-5515 685);
FORCEPROP 1 LASTPIN (-5525 675) BN 1
J 0
(-5577 683);
DISPLAY 0.617021 (-5577 683);
PAINT GREEN (-5577 683);
FORCEPROP 2 LAST CDS_LIB mstr_standard
J 0
(-5575 675);
PAINT MONO (-5575 675);
DISPLAY INVISIBLE (-5575 675);
FORCEPROP 1 LAST BODY_TYPE PLUMBING
J 0
(-5575 625);
DISPLAY 1.595745 (-5575 625);
PAINT GREEN (-5575 625);
DISPLAY INVISIBLE (-5575 625);
FORCEPROP 1 LAST HDL_TAP TRUE
J 0
(-5250 550);
DISPLAY 1.595745 (-5250 550);
PAINT GREEN (-5250 550);
DISPLAY INVISIBLE (-5250 550);
FORCEPROP 1 LAST PATH I6
J 0
(-5577 675);
DISPLAY 0.872340 (-5577 675);
PAINT GREEN (-5577 675);
DISPLAY INVISIBLE (-5577 675);
FORCEADD TAP..6
(-5575 3425);
FORCEPROP 3 LASTPIN (-5525 3425) SIG_NAME M_K_DQ<38>
J 0
(-5515 3435);
DISPLAY 0.659574 (-5515 3435);
PAINT MONO (-5515 3435);
DISPLAY INVISIBLE (-5515 3435);
FORCEPROP 1 LASTPIN (-5525 3425) BN 38
J 0
(-5577 3433);
DISPLAY 0.617021 (-5577 3433);
PAINT GREEN (-5577 3433);
FORCEPROP 2 LAST CDS_LIB mstr_standard
J 0
(-5575 3425);
PAINT MONO (-5575 3425);
DISPLAY INVISIBLE (-5575 3425);
FORCEPROP 1 LAST BODY_TYPE PLUMBING
J 0
(-5575 3375);
DISPLAY 1.595745 (-5575 3375);
PAINT GREEN (-5575 3375);
DISPLAY INVISIBLE (-5575 3375);
FORCEPROP 1 LAST HDL_TAP TRUE
J 0
(-5250 3300);
DISPLAY 1.595745 (-5250 3300);
PAINT GREEN (-5250 3300);
DISPLAY INVISIBLE (-5250 3300);
FORCEPROP 1 LAST PATH I60
J 0
(-5577 3425);
DISPLAY 0.872340 (-5577 3425);
PAINT GREEN (-5577 3425);
DISPLAY INVISIBLE (-5577 3425);
FORCEADD TAP..6
(-5575 3475);
FORCEPROP 3 LASTPIN (-5525 3475) SIG_NAME M_K_DQ<39>
J 0
(-5515 3485);
DISPLAY 0.659574 (-5515 3485);
PAINT MONO (-5515 3485);
DISPLAY INVISIBLE (-5515 3485);
FORCEPROP 1 LASTPIN (-5525 3475) BN 39
J 0
(-5577 3483);
DISPLAY 0.617021 (-5577 3483);
PAINT GREEN (-5577 3483);
FORCEPROP 2 LAST CDS_LIB mstr_standard
J 0
(-5575 3475);
PAINT MONO (-5575 3475);
DISPLAY INVISIBLE (-5575 3475);
FORCEPROP 1 LAST BODY_TYPE PLUMBING
J 0
(-5575 3425);
DISPLAY 1.595745 (-5575 3425);
PAINT GREEN (-5575 3425);
DISPLAY INVISIBLE (-5575 3425);
FORCEPROP 1 LAST HDL_TAP TRUE
J 0
(-5250 3350);
DISPLAY 1.595745 (-5250 3350);
PAINT GREEN (-5250 3350);
DISPLAY INVISIBLE (-5250 3350);
FORCEPROP 1 LAST PATH I61
J 0
(-5577 3475);
DISPLAY 0.872340 (-5577 3475);
PAINT GREEN (-5577 3475);
DISPLAY INVISIBLE (-5577 3475);
FORCEADD TAP..6
(-5575 3525);
FORCEPROP 3 LASTPIN (-5525 3525) SIG_NAME M_K_DQ<40>
J 0
(-5515 3535);
DISPLAY 0.659574 (-5515 3535);
PAINT MONO (-5515 3535);
DISPLAY INVISIBLE (-5515 3535);
FORCEPROP 1 LASTPIN (-5525 3525) BN 40
J 0
(-5577 3533);
DISPLAY 0.617021 (-5577 3533);
PAINT GREEN (-5577 3533);
FORCEPROP 2 LAST CDS_LIB mstr_standard
J 0
(-5575 3525);
PAINT MONO (-5575 3525);
DISPLAY INVISIBLE (-5575 3525);
FORCEPROP 1 LAST BODY_TYPE PLUMBING
J 0
(-5575 3475);
DISPLAY 1.595745 (-5575 3475);
PAINT GREEN (-5575 3475);
DISPLAY INVISIBLE (-5575 3475);
FORCEPROP 1 LAST HDL_TAP TRUE
J 0
(-5250 3400);
DISPLAY 1.595745 (-5250 3400);
PAINT GREEN (-5250 3400);
DISPLAY INVISIBLE (-5250 3400);
FORCEPROP 1 LAST PATH I62
J 0
(-5577 3525);
DISPLAY 0.872340 (-5577 3525);
PAINT GREEN (-5577 3525);
DISPLAY INVISIBLE (-5577 3525);
FORCEADD TAP..6
(-5575 3575);
FORCEPROP 3 LASTPIN (-5525 3575) SIG_NAME M_K_DQ<41>
J 0
(-5515 3585);
DISPLAY 0.659574 (-5515 3585);
PAINT MONO (-5515 3585);
DISPLAY INVISIBLE (-5515 3585);
FORCEPROP 1 LASTPIN (-5525 3575) BN 41
J 0
(-5577 3583);
DISPLAY 0.617021 (-5577 3583);
PAINT GREEN (-5577 3583);
FORCEPROP 2 LAST CDS_LIB mstr_standard
J 0
(-5575 3575);
PAINT MONO (-5575 3575);
DISPLAY INVISIBLE (-5575 3575);
FORCEPROP 1 LAST BODY_TYPE PLUMBING
J 0
(-5575 3525);
DISPLAY 1.595745 (-5575 3525);
PAINT GREEN (-5575 3525);
DISPLAY INVISIBLE (-5575 3525);
FORCEPROP 1 LAST HDL_TAP TRUE
J 0
(-5250 3450);
DISPLAY 1.595745 (-5250 3450);
PAINT GREEN (-5250 3450);
DISPLAY INVISIBLE (-5250 3450);
FORCEPROP 1 LAST PATH I63
J 0
(-5577 3575);
DISPLAY 0.872340 (-5577 3575);
PAINT GREEN (-5577 3575);
DISPLAY INVISIBLE (-5577 3575);
FORCEADD TAP..6
(-5575 3625);
FORCEPROP 3 LASTPIN (-5525 3625) SIG_NAME M_K_DQ<42>
J 0
(-5515 3635);
DISPLAY 0.659574 (-5515 3635);
PAINT MONO (-5515 3635);
DISPLAY INVISIBLE (-5515 3635);
FORCEPROP 1 LASTPIN (-5525 3625) BN 42
J 0
(-5577 3633);
DISPLAY 0.617021 (-5577 3633);
PAINT GREEN (-5577 3633);
FORCEPROP 2 LAST CDS_LIB mstr_standard
J 0
(-5575 3625);
PAINT MONO (-5575 3625);
DISPLAY INVISIBLE (-5575 3625);
FORCEPROP 1 LAST BODY_TYPE PLUMBING
J 0
(-5575 3575);
DISPLAY 1.595745 (-5575 3575);
PAINT GREEN (-5575 3575);
DISPLAY INVISIBLE (-5575 3575);
FORCEPROP 1 LAST HDL_TAP TRUE
J 0
(-5250 3500);
DISPLAY 1.595745 (-5250 3500);
PAINT GREEN (-5250 3500);
DISPLAY INVISIBLE (-5250 3500);
FORCEPROP 1 LAST PATH I64
J 0
(-5577 3625);
DISPLAY 0.872340 (-5577 3625);
PAINT GREEN (-5577 3625);
DISPLAY INVISIBLE (-5577 3625);
FORCEADD TAP..6
(-5575 3675);
FORCEPROP 3 LASTPIN (-5525 3675) SIG_NAME M_K_DQ<43>
J 0
(-5515 3685);
DISPLAY 0.659574 (-5515 3685);
PAINT MONO (-5515 3685);
DISPLAY INVISIBLE (-5515 3685);
FORCEPROP 1 LASTPIN (-5525 3675) BN 43
J 0
(-5577 3683);
DISPLAY 0.617021 (-5577 3683);
PAINT GREEN (-5577 3683);
FORCEPROP 2 LAST CDS_LIB mstr_standard
J 0
(-5575 3675);
PAINT MONO (-5575 3675);
DISPLAY INVISIBLE (-5575 3675);
FORCEPROP 1 LAST BODY_TYPE PLUMBING
J 0
(-5575 3625);
DISPLAY 1.595745 (-5575 3625);
PAINT GREEN (-5575 3625);
DISPLAY INVISIBLE (-5575 3625);
FORCEPROP 1 LAST HDL_TAP TRUE
J 0
(-5250 3550);
DISPLAY 1.595745 (-5250 3550);
PAINT GREEN (-5250 3550);
DISPLAY INVISIBLE (-5250 3550);
FORCEPROP 1 LAST PATH I65
J 0
(-5577 3675);
DISPLAY 0.872340 (-5577 3675);
PAINT GREEN (-5577 3675);
DISPLAY INVISIBLE (-5577 3675);
FORCEADD TAP..6
(-5575 3725);
FORCEPROP 3 LASTPIN (-5525 3725) SIG_NAME M_K_DQ<44>
J 0
(-5515 3735);
DISPLAY 0.659574 (-5515 3735);
PAINT MONO (-5515 3735);
DISPLAY INVISIBLE (-5515 3735);
FORCEPROP 1 LASTPIN (-5525 3725) BN 44
J 0
(-5577 3733);
DISPLAY 0.617021 (-5577 3733);
PAINT GREEN (-5577 3733);
FORCEPROP 2 LAST CDS_LIB mstr_standard
J 0
(-5575 3725);
PAINT MONO (-5575 3725);
DISPLAY INVISIBLE (-5575 3725);
FORCEPROP 1 LAST BODY_TYPE PLUMBING
J 0
(-5575 3675);
DISPLAY 1.595745 (-5575 3675);
PAINT GREEN (-5575 3675);
DISPLAY INVISIBLE (-5575 3675);
FORCEPROP 1 LAST HDL_TAP TRUE
J 0
(-5250 3600);
DISPLAY 1.595745 (-5250 3600);
PAINT GREEN (-5250 3600);
DISPLAY INVISIBLE (-5250 3600);
FORCEPROP 1 LAST PATH I66
J 0
(-5577 3725);
DISPLAY 0.872340 (-5577 3725);
PAINT GREEN (-5577 3725);
DISPLAY INVISIBLE (-5577 3725);
FORCEADD TAP..6
(-5575 3775);
FORCEPROP 3 LASTPIN (-5525 3775) SIG_NAME M_K_DQ<45>
J 0
(-5515 3785);
DISPLAY 0.659574 (-5515 3785);
PAINT MONO (-5515 3785);
DISPLAY INVISIBLE (-5515 3785);
FORCEPROP 1 LASTPIN (-5525 3775) BN 45
J 0
(-5577 3783);
DISPLAY 0.617021 (-5577 3783);
PAINT GREEN (-5577 3783);
FORCEPROP 2 LAST CDS_LIB mstr_standard
J 0
(-5575 3775);
PAINT MONO (-5575 3775);
DISPLAY INVISIBLE (-5575 3775);
FORCEPROP 1 LAST BODY_TYPE PLUMBING
J 0
(-5575 3725);
DISPLAY 1.595745 (-5575 3725);
PAINT GREEN (-5575 3725);
DISPLAY INVISIBLE (-5575 3725);
FORCEPROP 1 LAST HDL_TAP TRUE
J 0
(-5250 3650);
DISPLAY 1.595745 (-5250 3650);
PAINT GREEN (-5250 3650);
DISPLAY INVISIBLE (-5250 3650);
FORCEPROP 1 LAST PATH I67
J 0
(-5577 3775);
DISPLAY 0.872340 (-5577 3775);
PAINT GREEN (-5577 3775);
DISPLAY INVISIBLE (-5577 3775);
FORCEADD TAP..6
(-5575 3825);
FORCEPROP 3 LASTPIN (-5525 3825) SIG_NAME M_K_DQ<46>
J 0
(-5515 3835);
DISPLAY 0.659574 (-5515 3835);
PAINT MONO (-5515 3835);
DISPLAY INVISIBLE (-5515 3835);
FORCEPROP 1 LASTPIN (-5525 3825) BN 46
J 0
(-5577 3833);
DISPLAY 0.617021 (-5577 3833);
PAINT GREEN (-5577 3833);
FORCEPROP 2 LAST CDS_LIB mstr_standard
J 0
(-5575 3825);
PAINT MONO (-5575 3825);
DISPLAY INVISIBLE (-5575 3825);
FORCEPROP 1 LAST BODY_TYPE PLUMBING
J 0
(-5575 3775);
DISPLAY 1.595745 (-5575 3775);
PAINT GREEN (-5575 3775);
DISPLAY INVISIBLE (-5575 3775);
FORCEPROP 1 LAST HDL_TAP TRUE
J 0
(-5250 3700);
DISPLAY 1.595745 (-5250 3700);
PAINT GREEN (-5250 3700);
DISPLAY INVISIBLE (-5250 3700);
FORCEPROP 1 LAST PATH I68
J 0
(-5577 3825);
DISPLAY 0.872340 (-5577 3825);
PAINT GREEN (-5577 3825);
DISPLAY INVISIBLE (-5577 3825);
FORCEADD TAP..6
(-5575 3875);
FORCEPROP 3 LASTPIN (-5525 3875) SIG_NAME M_K_DQ<47>
J 0
(-5515 3885);
DISPLAY 0.659574 (-5515 3885);
PAINT MONO (-5515 3885);
DISPLAY INVISIBLE (-5515 3885);
FORCEPROP 1 LASTPIN (-5525 3875) BN 47
J 0
(-5577 3883);
DISPLAY 0.617021 (-5577 3883);
PAINT GREEN (-5577 3883);
FORCEPROP 2 LAST CDS_LIB mstr_standard
J 0
(-5575 3875);
PAINT MONO (-5575 3875);
DISPLAY INVISIBLE (-5575 3875);
FORCEPROP 1 LAST BODY_TYPE PLUMBING
J 0
(-5575 3825);
DISPLAY 1.595745 (-5575 3825);
PAINT GREEN (-5575 3825);
DISPLAY INVISIBLE (-5575 3825);
FORCEPROP 1 LAST HDL_TAP TRUE
J 0
(-5250 3750);
DISPLAY 1.595745 (-5250 3750);
PAINT GREEN (-5250 3750);
DISPLAY INVISIBLE (-5250 3750);
FORCEPROP 1 LAST PATH I69
J 0
(-5577 3875);
DISPLAY 0.872340 (-5577 3875);
PAINT GREEN (-5577 3875);
DISPLAY INVISIBLE (-5577 3875);
FORCEADD TAP..6
(-5575 775);
FORCEPROP 3 LASTPIN (-5525 775) SIG_NAME M_K_CLK_DN<3>
J 0
(-5515 785);
DISPLAY 0.659574 (-5515 785);
PAINT MONO (-5515 785);
DISPLAY INVISIBLE (-5515 785);
FORCEPROP 1 LASTPIN (-5525 775) BN 3
J 0
(-5577 783);
DISPLAY 0.617021 (-5577 783);
PAINT GREEN (-5577 783);
FORCEPROP 2 LAST CDS_LIB mstr_standard
J 0
(-5575 775);
PAINT MONO (-5575 775);
DISPLAY INVISIBLE (-5575 775);
FORCEPROP 1 LAST BODY_TYPE PLUMBING
J 0
(-5575 725);
DISPLAY 1.595745 (-5575 725);
PAINT GREEN (-5575 725);
DISPLAY INVISIBLE (-5575 725);
FORCEPROP 1 LAST HDL_TAP TRUE
J 0
(-5250 650);
DISPLAY 1.595745 (-5250 650);
PAINT GREEN (-5250 650);
DISPLAY INVISIBLE (-5250 650);
FORCEPROP 1 LAST PATH I7
J 0
(-5577 775);
DISPLAY 0.872340 (-5577 775);
PAINT GREEN (-5577 775);
DISPLAY INVISIBLE (-5577 775);
FORCEADD TAP..6
(-5575 3925);
FORCEPROP 3 LASTPIN (-5525 3925) SIG_NAME M_K_DQ<48>
J 0
(-5515 3935);
DISPLAY 0.659574 (-5515 3935);
PAINT MONO (-5515 3935);
DISPLAY INVISIBLE (-5515 3935);
FORCEPROP 1 LASTPIN (-5525 3925) BN 48
J 0
(-5577 3933);
DISPLAY 0.617021 (-5577 3933);
PAINT GREEN (-5577 3933);
FORCEPROP 2 LAST CDS_LIB mstr_standard
J 0
(-5575 3925);
PAINT MONO (-5575 3925);
DISPLAY INVISIBLE (-5575 3925);
FORCEPROP 1 LAST BODY_TYPE PLUMBING
J 0
(-5575 3875);
DISPLAY 1.595745 (-5575 3875);
PAINT GREEN (-5575 3875);
DISPLAY INVISIBLE (-5575 3875);
FORCEPROP 1 LAST HDL_TAP TRUE
J 0
(-5250 3800);
DISPLAY 1.595745 (-5250 3800);
PAINT GREEN (-5250 3800);
DISPLAY INVISIBLE (-5250 3800);
FORCEPROP 1 LAST PATH I70
J 0
(-5577 3925);
DISPLAY 0.872340 (-5577 3925);
PAINT GREEN (-5577 3925);
DISPLAY INVISIBLE (-5577 3925);
FORCEADD TAP..6
(-5575 3975);
FORCEPROP 3 LASTPIN (-5525 3975) SIG_NAME M_K_DQ<49>
J 0
(-5515 3985);
DISPLAY 0.659574 (-5515 3985);
PAINT MONO (-5515 3985);
DISPLAY INVISIBLE (-5515 3985);
FORCEPROP 1 LASTPIN (-5525 3975) BN 49
J 0
(-5577 3983);
DISPLAY 0.617021 (-5577 3983);
PAINT GREEN (-5577 3983);
FORCEPROP 2 LAST CDS_LIB mstr_standard
J 0
(-5575 3975);
PAINT MONO (-5575 3975);
DISPLAY INVISIBLE (-5575 3975);
FORCEPROP 1 LAST BODY_TYPE PLUMBING
J 0
(-5575 3925);
DISPLAY 1.595745 (-5575 3925);
PAINT GREEN (-5575 3925);
DISPLAY INVISIBLE (-5575 3925);
FORCEPROP 1 LAST HDL_TAP TRUE
J 0
(-5250 3850);
DISPLAY 1.595745 (-5250 3850);
PAINT GREEN (-5250 3850);
DISPLAY INVISIBLE (-5250 3850);
FORCEPROP 1 LAST PATH I71
J 0
(-5577 3975);
DISPLAY 0.872340 (-5577 3975);
PAINT GREEN (-5577 3975);
DISPLAY INVISIBLE (-5577 3975);
FORCEADD OFFPAGE..6
(-6425 4800);
FORCEPROP 2 LAST $XR1 84 
J 0
(-6764 4800);
DISPLAY 0.638298 (-6764 4800);
PAINT MONO (-6764 4800);
FORCEPROP 2 LAST $XR0 83 
J 0
(-6674 4800);
DISPLAY 0.638298 (-6674 4800);
PAINT MONO (-6674 4800);
FORCEPROP 2 LAST CDS_LIB mstr_standard
J 0
(-6425 4800);
PAINT MONO (-6425 4800);
DISPLAY INVISIBLE (-6425 4800);
FORCEPROP 1 LAST OFFPAGE TRUE
J 0
(-6100 4675);
DISPLAY 1.170213 (-6100 4675);
PAINT GREEN (-6100 4675);
DISPLAY INVISIBLE (-6100 4675);
FORCEPROP 1 LAST COMMENT_BODY TRUE
J 0
(-6325 4725);
DISPLAY 1.170213 (-6325 4725);
PAINT GREEN (-6325 4725);
DISPLAY INVISIBLE (-6325 4725);
FORCEPROP 2 LAST PATH I72
J 0
(-6375 4875);
DISPLAY 1.021277 (-6375 4875);
PAINT ORANGE (-6375 4875);
DISPLAY INVISIBLE (-6375 4875);
FORCEADD TAP..6
(-5575 4025);
FORCEPROP 3 LASTPIN (-5525 4025) SIG_NAME M_K_DQ<50>
J 0
(-5515 4035);
DISPLAY 0.659574 (-5515 4035);
PAINT MONO (-5515 4035);
DISPLAY INVISIBLE (-5515 4035);
FORCEPROP 1 LASTPIN (-5525 4025) BN 50
J 0
(-5577 4033);
DISPLAY 0.617021 (-5577 4033);
PAINT GREEN (-5577 4033);
FORCEPROP 2 LAST CDS_LIB mstr_standard
J 0
(-5575 4025);
PAINT MONO (-5575 4025);
DISPLAY INVISIBLE (-5575 4025);
FORCEPROP 1 LAST BODY_TYPE PLUMBING
J 0
(-5575 3975);
DISPLAY 1.595745 (-5575 3975);
PAINT GREEN (-5575 3975);
DISPLAY INVISIBLE (-5575 3975);
FORCEPROP 1 LAST HDL_TAP TRUE
J 0
(-5250 3900);
DISPLAY 1.595745 (-5250 3900);
PAINT GREEN (-5250 3900);
DISPLAY INVISIBLE (-5250 3900);
FORCEPROP 1 LAST PATH I73
J 0
(-5577 4025);
DISPLAY 0.872340 (-5577 4025);
PAINT GREEN (-5577 4025);
DISPLAY INVISIBLE (-5577 4025);
FORCEADD TAP..6
(-5575 4075);
FORCEPROP 3 LASTPIN (-5525 4075) SIG_NAME M_K_DQ<51>
J 0
(-5515 4085);
DISPLAY 0.659574 (-5515 4085);
PAINT MONO (-5515 4085);
DISPLAY INVISIBLE (-5515 4085);
FORCEPROP 1 LASTPIN (-5525 4075) BN 51
J 0
(-5577 4083);
DISPLAY 0.617021 (-5577 4083);
PAINT GREEN (-5577 4083);
FORCEPROP 2 LAST CDS_LIB mstr_standard
J 0
(-5575 4075);
PAINT MONO (-5575 4075);
DISPLAY INVISIBLE (-5575 4075);
FORCEPROP 1 LAST BODY_TYPE PLUMBING
J 0
(-5575 4025);
DISPLAY 1.595745 (-5575 4025);
PAINT GREEN (-5575 4025);
DISPLAY INVISIBLE (-5575 4025);
FORCEPROP 1 LAST HDL_TAP TRUE
J 0
(-5250 3950);
DISPLAY 1.595745 (-5250 3950);
PAINT GREEN (-5250 3950);
DISPLAY INVISIBLE (-5250 3950);
FORCEPROP 1 LAST PATH I74
J 0
(-5577 4075);
DISPLAY 0.872340 (-5577 4075);
PAINT GREEN (-5577 4075);
DISPLAY INVISIBLE (-5577 4075);
FORCEADD TAP..6
(-5575 4125);
FORCEPROP 3 LASTPIN (-5525 4125) SIG_NAME M_K_DQ<52>
J 0
(-5515 4135);
DISPLAY 0.659574 (-5515 4135);
PAINT MONO (-5515 4135);
DISPLAY INVISIBLE (-5515 4135);
FORCEPROP 1 LASTPIN (-5525 4125) BN 52
J 0
(-5577 4133);
DISPLAY 0.617021 (-5577 4133);
PAINT GREEN (-5577 4133);
FORCEPROP 2 LAST CDS_LIB mstr_standard
J 0
(-5575 4125);
PAINT MONO (-5575 4125);
DISPLAY INVISIBLE (-5575 4125);
FORCEPROP 1 LAST BODY_TYPE PLUMBING
J 0
(-5575 4075);
DISPLAY 1.595745 (-5575 4075);
PAINT GREEN (-5575 4075);
DISPLAY INVISIBLE (-5575 4075);
FORCEPROP 1 LAST HDL_TAP TRUE
J 0
(-5250 4000);
DISPLAY 1.595745 (-5250 4000);
PAINT GREEN (-5250 4000);
DISPLAY INVISIBLE (-5250 4000);
FORCEPROP 1 LAST PATH I75
J 0
(-5577 4125);
DISPLAY 0.872340 (-5577 4125);
PAINT GREEN (-5577 4125);
DISPLAY INVISIBLE (-5577 4125);
FORCEADD TAP..6
(-5575 4175);
FORCEPROP 3 LASTPIN (-5525 4175) SIG_NAME M_K_DQ<53>
J 0
(-5515 4185);
DISPLAY 0.659574 (-5515 4185);
PAINT MONO (-5515 4185);
DISPLAY INVISIBLE (-5515 4185);
FORCEPROP 1 LASTPIN (-5525 4175) BN 53
J 0
(-5577 4183);
DISPLAY 0.617021 (-5577 4183);
PAINT GREEN (-5577 4183);
FORCEPROP 2 LAST CDS_LIB mstr_standard
J 0
(-5575 4175);
PAINT MONO (-5575 4175);
DISPLAY INVISIBLE (-5575 4175);
FORCEPROP 1 LAST BODY_TYPE PLUMBING
J 0
(-5575 4125);
DISPLAY 1.595745 (-5575 4125);
PAINT GREEN (-5575 4125);
DISPLAY INVISIBLE (-5575 4125);
FORCEPROP 1 LAST HDL_TAP TRUE
J 0
(-5250 4050);
DISPLAY 1.595745 (-5250 4050);
PAINT GREEN (-5250 4050);
DISPLAY INVISIBLE (-5250 4050);
FORCEPROP 1 LAST PATH I76
J 0
(-5577 4175);
DISPLAY 0.872340 (-5577 4175);
PAINT GREEN (-5577 4175);
DISPLAY INVISIBLE (-5577 4175);
FORCEADD TAP..6
(-5575 4225);
FORCEPROP 3 LASTPIN (-5525 4225) SIG_NAME M_K_DQ<54>
J 0
(-5515 4235);
DISPLAY 0.659574 (-5515 4235);
PAINT MONO (-5515 4235);
DISPLAY INVISIBLE (-5515 4235);
FORCEPROP 1 LASTPIN (-5525 4225) BN 54
J 0
(-5577 4233);
DISPLAY 0.617021 (-5577 4233);
PAINT GREEN (-5577 4233);
FORCEPROP 2 LAST CDS_LIB mstr_standard
J 0
(-5575 4225);
PAINT MONO (-5575 4225);
DISPLAY INVISIBLE (-5575 4225);
FORCEPROP 1 LAST BODY_TYPE PLUMBING
J 0
(-5575 4175);
DISPLAY 1.595745 (-5575 4175);
PAINT GREEN (-5575 4175);
DISPLAY INVISIBLE (-5575 4175);
FORCEPROP 1 LAST HDL_TAP TRUE
J 0
(-5250 4100);
DISPLAY 1.595745 (-5250 4100);
PAINT GREEN (-5250 4100);
DISPLAY INVISIBLE (-5250 4100);
FORCEPROP 1 LAST PATH I77
J 0
(-5577 4225);
DISPLAY 0.872340 (-5577 4225);
PAINT GREEN (-5577 4225);
DISPLAY INVISIBLE (-5577 4225);
FORCEADD TAP..6
(-5575 4275);
FORCEPROP 3 LASTPIN (-5525 4275) SIG_NAME M_K_DQ<55>
J 0
(-5515 4285);
DISPLAY 0.659574 (-5515 4285);
PAINT MONO (-5515 4285);
DISPLAY INVISIBLE (-5515 4285);
FORCEPROP 1 LASTPIN (-5525 4275) BN 55
J 0
(-5577 4283);
DISPLAY 0.617021 (-5577 4283);
PAINT GREEN (-5577 4283);
FORCEPROP 2 LAST CDS_LIB mstr_standard
J 0
(-5575 4275);
PAINT MONO (-5575 4275);
DISPLAY INVISIBLE (-5575 4275);
FORCEPROP 1 LAST BODY_TYPE PLUMBING
J 0
(-5575 4225);
DISPLAY 1.595745 (-5575 4225);
PAINT GREEN (-5575 4225);
DISPLAY INVISIBLE (-5575 4225);
FORCEPROP 1 LAST HDL_TAP TRUE
J 0
(-5250 4150);
DISPLAY 1.595745 (-5250 4150);
PAINT GREEN (-5250 4150);
DISPLAY INVISIBLE (-5250 4150);
FORCEPROP 1 LAST PATH I78
J 0
(-5577 4275);
DISPLAY 0.872340 (-5577 4275);
PAINT GREEN (-5577 4275);
DISPLAY INVISIBLE (-5577 4275);
FORCEADD TAP..6
(-5575 4325);
FORCEPROP 3 LASTPIN (-5525 4325) SIG_NAME M_K_DQ<56>
J 0
(-5515 4335);
DISPLAY 0.659574 (-5515 4335);
PAINT MONO (-5515 4335);
DISPLAY INVISIBLE (-5515 4335);
FORCEPROP 1 LASTPIN (-5525 4325) BN 56
J 0
(-5577 4333);
DISPLAY 0.617021 (-5577 4333);
PAINT GREEN (-5577 4333);
FORCEPROP 2 LAST CDS_LIB mstr_standard
J 0
(-5575 4325);
PAINT MONO (-5575 4325);
DISPLAY INVISIBLE (-5575 4325);
FORCEPROP 1 LAST BODY_TYPE PLUMBING
J 0
(-5575 4275);
DISPLAY 1.595745 (-5575 4275);
PAINT GREEN (-5575 4275);
DISPLAY INVISIBLE (-5575 4275);
FORCEPROP 1 LAST HDL_TAP TRUE
J 0
(-5250 4200);
DISPLAY 1.595745 (-5250 4200);
PAINT GREEN (-5250 4200);
DISPLAY INVISIBLE (-5250 4200);
FORCEPROP 1 LAST PATH I79
J 0
(-5577 4325);
DISPLAY 0.872340 (-5577 4325);
PAINT GREEN (-5577 4325);
DISPLAY INVISIBLE (-5577 4325);
FORCEADD TAP..6
(-5575 725);
FORCEPROP 3 LASTPIN (-5525 725) SIG_NAME M_K_CLK_DN<2>
J 0
(-5515 735);
DISPLAY 0.659574 (-5515 735);
PAINT MONO (-5515 735);
DISPLAY INVISIBLE (-5515 735);
FORCEPROP 1 LASTPIN (-5525 725) BN 2
J 0
(-5577 733);
DISPLAY 0.617021 (-5577 733);
PAINT GREEN (-5577 733);
FORCEPROP 2 LAST CDS_LIB mstr_standard
J 0
(-5575 725);
PAINT MONO (-5575 725);
DISPLAY INVISIBLE (-5575 725);
FORCEPROP 1 LAST BODY_TYPE PLUMBING
J 0
(-5575 675);
DISPLAY 1.595745 (-5575 675);
PAINT GREEN (-5575 675);
DISPLAY INVISIBLE (-5575 675);
FORCEPROP 1 LAST HDL_TAP TRUE
J 0
(-5250 600);
DISPLAY 1.595745 (-5250 600);
PAINT GREEN (-5250 600);
DISPLAY INVISIBLE (-5250 600);
FORCEPROP 1 LAST PATH I8
J 0
(-5577 725);
DISPLAY 0.872340 (-5577 725);
PAINT GREEN (-5577 725);
DISPLAY INVISIBLE (-5577 725);
FORCEADD TAP..6
(-5575 4375);
FORCEPROP 3 LASTPIN (-5525 4375) SIG_NAME M_K_DQ<57>
J 0
(-5515 4385);
DISPLAY 0.659574 (-5515 4385);
PAINT MONO (-5515 4385);
DISPLAY INVISIBLE (-5515 4385);
FORCEPROP 1 LASTPIN (-5525 4375) BN 57
J 0
(-5577 4383);
DISPLAY 0.617021 (-5577 4383);
PAINT GREEN (-5577 4383);
FORCEPROP 2 LAST CDS_LIB mstr_standard
J 0
(-5575 4375);
PAINT MONO (-5575 4375);
DISPLAY INVISIBLE (-5575 4375);
FORCEPROP 1 LAST BODY_TYPE PLUMBING
J 0
(-5575 4325);
DISPLAY 1.595745 (-5575 4325);
PAINT GREEN (-5575 4325);
DISPLAY INVISIBLE (-5575 4325);
FORCEPROP 1 LAST HDL_TAP TRUE
J 0
(-5250 4250);
DISPLAY 1.595745 (-5250 4250);
PAINT GREEN (-5250 4250);
DISPLAY INVISIBLE (-5250 4250);
FORCEPROP 1 LAST PATH I80
J 0
(-5577 4375);
DISPLAY 0.872340 (-5577 4375);
PAINT GREEN (-5577 4375);
DISPLAY INVISIBLE (-5577 4375);
FORCEADD TAP..6
(-5575 4425);
FORCEPROP 3 LASTPIN (-5525 4425) SIG_NAME M_K_DQ<58>
J 0
(-5515 4435);
DISPLAY 0.659574 (-5515 4435);
PAINT MONO (-5515 4435);
DISPLAY INVISIBLE (-5515 4435);
FORCEPROP 1 LASTPIN (-5525 4425) BN 58
J 0
(-5577 4433);
DISPLAY 0.617021 (-5577 4433);
PAINT GREEN (-5577 4433);
FORCEPROP 2 LAST CDS_LIB mstr_standard
J 0
(-5575 4425);
PAINT MONO (-5575 4425);
DISPLAY INVISIBLE (-5575 4425);
FORCEPROP 1 LAST BODY_TYPE PLUMBING
J 0
(-5575 4375);
DISPLAY 1.595745 (-5575 4375);
PAINT GREEN (-5575 4375);
DISPLAY INVISIBLE (-5575 4375);
FORCEPROP 1 LAST HDL_TAP TRUE
J 0
(-5250 4300);
DISPLAY 1.595745 (-5250 4300);
PAINT GREEN (-5250 4300);
DISPLAY INVISIBLE (-5250 4300);
FORCEPROP 1 LAST PATH I81
J 0
(-5577 4425);
DISPLAY 0.872340 (-5577 4425);
PAINT GREEN (-5577 4425);
DISPLAY INVISIBLE (-5577 4425);
FORCEADD TAP..6
(-5575 4475);
FORCEPROP 3 LASTPIN (-5525 4475) SIG_NAME M_K_DQ<59>
J 0
(-5515 4485);
DISPLAY 0.659574 (-5515 4485);
PAINT MONO (-5515 4485);
DISPLAY INVISIBLE (-5515 4485);
FORCEPROP 1 LASTPIN (-5525 4475) BN 59
J 0
(-5577 4483);
DISPLAY 0.617021 (-5577 4483);
PAINT GREEN (-5577 4483);
FORCEPROP 2 LAST CDS_LIB mstr_standard
J 0
(-5575 4475);
PAINT MONO (-5575 4475);
DISPLAY INVISIBLE (-5575 4475);
FORCEPROP 1 LAST BODY_TYPE PLUMBING
J 0
(-5575 4425);
DISPLAY 1.595745 (-5575 4425);
PAINT GREEN (-5575 4425);
DISPLAY INVISIBLE (-5575 4425);
FORCEPROP 1 LAST HDL_TAP TRUE
J 0
(-5250 4350);
DISPLAY 1.595745 (-5250 4350);
PAINT GREEN (-5250 4350);
DISPLAY INVISIBLE (-5250 4350);
FORCEPROP 1 LAST PATH I82
J 0
(-5577 4475);
DISPLAY 0.872340 (-5577 4475);
PAINT GREEN (-5577 4475);
DISPLAY INVISIBLE (-5577 4475);
FORCEADD TAP..6
(-5575 4525);
FORCEPROP 3 LASTPIN (-5525 4525) SIG_NAME M_K_DQ<60>
J 0
(-5515 4535);
DISPLAY 0.659574 (-5515 4535);
PAINT MONO (-5515 4535);
DISPLAY INVISIBLE (-5515 4535);
FORCEPROP 1 LASTPIN (-5525 4525) BN 60
J 0
(-5577 4533);
DISPLAY 0.617021 (-5577 4533);
PAINT GREEN (-5577 4533);
FORCEPROP 2 LAST CDS_LIB mstr_standard
J 0
(-5575 4525);
PAINT MONO (-5575 4525);
DISPLAY INVISIBLE (-5575 4525);
FORCEPROP 1 LAST BODY_TYPE PLUMBING
J 0
(-5575 4475);
DISPLAY 1.595745 (-5575 4475);
PAINT GREEN (-5575 4475);
DISPLAY INVISIBLE (-5575 4475);
FORCEPROP 1 LAST HDL_TAP TRUE
J 0
(-5250 4400);
DISPLAY 1.595745 (-5250 4400);
PAINT GREEN (-5250 4400);
DISPLAY INVISIBLE (-5250 4400);
FORCEPROP 1 LAST PATH I83
J 0
(-5577 4525);
DISPLAY 0.872340 (-5577 4525);
PAINT GREEN (-5577 4525);
DISPLAY INVISIBLE (-5577 4525);
FORCEADD TAP..6
(-5575 4575);
FORCEPROP 3 LASTPIN (-5525 4575) SIG_NAME M_K_DQ<61>
J 0
(-5515 4585);
DISPLAY 0.659574 (-5515 4585);
PAINT MONO (-5515 4585);
DISPLAY INVISIBLE (-5515 4585);
FORCEPROP 1 LASTPIN (-5525 4575) BN 61
J 0
(-5577 4583);
DISPLAY 0.617021 (-5577 4583);
PAINT GREEN (-5577 4583);
FORCEPROP 2 LAST CDS_LIB mstr_standard
J 0
(-5575 4575);
PAINT MONO (-5575 4575);
DISPLAY INVISIBLE (-5575 4575);
FORCEPROP 1 LAST BODY_TYPE PLUMBING
J 0
(-5575 4525);
DISPLAY 1.595745 (-5575 4525);
PAINT GREEN (-5575 4525);
DISPLAY INVISIBLE (-5575 4525);
FORCEPROP 1 LAST HDL_TAP TRUE
J 0
(-5250 4450);
DISPLAY 1.595745 (-5250 4450);
PAINT GREEN (-5250 4450);
DISPLAY INVISIBLE (-5250 4450);
FORCEPROP 1 LAST PATH I84
J 0
(-5577 4575);
DISPLAY 0.872340 (-5577 4575);
PAINT GREEN (-5577 4575);
DISPLAY INVISIBLE (-5577 4575);
FORCEADD TAP..6
(-5575 4625);
FORCEPROP 3 LASTPIN (-5525 4625) SIG_NAME M_K_DQ<62>
J 0
(-5515 4635);
DISPLAY 0.659574 (-5515 4635);
PAINT MONO (-5515 4635);
DISPLAY INVISIBLE (-5515 4635);
FORCEPROP 1 LASTPIN (-5525 4625) BN 62
J 0
(-5577 4633);
DISPLAY 0.617021 (-5577 4633);
PAINT GREEN (-5577 4633);
FORCEPROP 2 LAST CDS_LIB mstr_standard
J 0
(-5575 4625);
PAINT MONO (-5575 4625);
DISPLAY INVISIBLE (-5575 4625);
FORCEPROP 1 LAST BODY_TYPE PLUMBING
J 0
(-5575 4575);
DISPLAY 1.595745 (-5575 4575);
PAINT GREEN (-5575 4575);
DISPLAY INVISIBLE (-5575 4575);
FORCEPROP 1 LAST HDL_TAP TRUE
J 0
(-5250 4500);
DISPLAY 1.595745 (-5250 4500);
PAINT GREEN (-5250 4500);
DISPLAY INVISIBLE (-5250 4500);
FORCEPROP 1 LAST PATH I85
J 0
(-5577 4625);
DISPLAY 0.872340 (-5577 4625);
PAINT GREEN (-5577 4625);
DISPLAY INVISIBLE (-5577 4625);
FORCEADD TAP..6
(-5575 4675);
FORCEPROP 3 LASTPIN (-5525 4675) SIG_NAME M_K_DQ<63>
J 0
(-5515 4685);
DISPLAY 0.659574 (-5515 4685);
PAINT MONO (-5515 4685);
DISPLAY INVISIBLE (-5515 4685);
FORCEPROP 1 LASTPIN (-5525 4675) BN 63
J 0
(-5577 4683);
DISPLAY 0.617021 (-5577 4683);
PAINT GREEN (-5577 4683);
FORCEPROP 2 LAST CDS_LIB mstr_standard
J 0
(-5575 4675);
PAINT MONO (-5575 4675);
DISPLAY INVISIBLE (-5575 4675);
FORCEPROP 1 LAST BODY_TYPE PLUMBING
J 0
(-5575 4625);
DISPLAY 1.595745 (-5575 4625);
PAINT GREEN (-5575 4625);
DISPLAY INVISIBLE (-5575 4625);
FORCEPROP 1 LAST HDL_TAP TRUE
J 0
(-5250 4550);
DISPLAY 1.595745 (-5250 4550);
PAINT GREEN (-5250 4550);
DISPLAY INVISIBLE (-5250 4550);
FORCEPROP 1 LAST PATH I86
J 0
(-5577 4675);
DISPLAY 0.872340 (-5577 4675);
PAINT GREEN (-5577 4675);
DISPLAY INVISIBLE (-5577 4675);
FORCEADD TAP..6
R 2
(-2850 775);
FORCEPROP 3 LASTPIN (-2900 775) SIG_NAME M_K_BA<1>
J 0
(-2890 785);
DISPLAY 0.659574 (-2890 785);
PAINT MONO (-2890 785);
DISPLAY INVISIBLE (-2890 785);
FORCEPROP 1 LASTPIN (-2900 775) BN 1
J 2
(-2848 783);
DISPLAY 0.617021 (-2848 783);
PAINT GREEN (-2848 783);
FORCEPROP 2 LAST CDS_LIB mstr_standard
J 0
(-2850 775);
PAINT MONO (-2850 775);
DISPLAY INVISIBLE (-2850 775);
FORCEPROP 1 LAST BODY_TYPE PLUMBING
J 2
(-2850 725);
DISPLAY 1.595745 (-2850 725);
PAINT GREEN (-2850 725);
DISPLAY INVISIBLE (-2850 725);
FORCEPROP 1 LAST HDL_TAP TRUE
J 2
(-3175 650);
DISPLAY 1.595745 (-3175 650);
PAINT GREEN (-3175 650);
DISPLAY INVISIBLE (-3175 650);
FORCEPROP 1 LAST PATH I87
J 2
(-2848 775);
DISPLAY 0.872340 (-2848 775);
PAINT GREEN (-2848 775);
DISPLAY INVISIBLE (-2848 775);
FORCEADD TAP..6
R 2
(-2850 725);
FORCEPROP 3 LASTPIN (-2900 725) SIG_NAME M_K_BA<0>
J 0
(-2890 735);
DISPLAY 0.659574 (-2890 735);
PAINT MONO (-2890 735);
DISPLAY INVISIBLE (-2890 735);
FORCEPROP 1 LASTPIN (-2900 725) BN 0
J 2
(-2848 733);
DISPLAY 0.617021 (-2848 733);
PAINT GREEN (-2848 733);
FORCEPROP 2 LAST CDS_LIB mstr_standard
J 0
(-2850 725);
PAINT MONO (-2850 725);
DISPLAY INVISIBLE (-2850 725);
FORCEPROP 1 LAST BODY_TYPE PLUMBING
J 2
(-2850 675);
DISPLAY 1.595745 (-2850 675);
PAINT GREEN (-2850 675);
DISPLAY INVISIBLE (-2850 675);
FORCEPROP 1 LAST HDL_TAP TRUE
J 2
(-3175 600);
DISPLAY 1.595745 (-3175 600);
PAINT GREEN (-3175 600);
DISPLAY INVISIBLE (-3175 600);
FORCEPROP 1 LAST PATH I88
J 2
(-2848 725);
DISPLAY 0.872340 (-2848 725);
PAINT GREEN (-2848 725);
DISPLAY INVISIBLE (-2848 725);
FORCEADD TAP..6
R 2
(-2850 825);
FORCEPROP 3 LASTPIN (-2900 825) SIG_NAME M_K_BG<0>
J 0
(-2890 835);
DISPLAY 0.659574 (-2890 835);
PAINT MONO (-2890 835);
DISPLAY INVISIBLE (-2890 835);
FORCEPROP 1 LASTPIN (-2900 825) BN 0
J 2
(-2848 833);
DISPLAY 0.617021 (-2848 833);
PAINT GREEN (-2848 833);
FORCEPROP 2 LAST CDS_LIB mstr_standard
J 0
(-2850 825);
PAINT MONO (-2850 825);
DISPLAY INVISIBLE (-2850 825);
FORCEPROP 1 LAST BODY_TYPE PLUMBING
J 2
(-2850 775);
DISPLAY 1.595745 (-2850 775);
PAINT GREEN (-2850 775);
DISPLAY INVISIBLE (-2850 775);
FORCEPROP 1 LAST HDL_TAP TRUE
J 2
(-3175 700);
DISPLAY 1.595745 (-3175 700);
PAINT GREEN (-3175 700);
DISPLAY INVISIBLE (-3175 700);
FORCEPROP 1 LAST PATH I89
J 2
(-2848 825);
DISPLAY 0.872340 (-2848 825);
PAINT GREEN (-2848 825);
DISPLAY INVISIBLE (-2848 825);
FORCEADD TAP..6
(-5575 875);
FORCEPROP 3 LASTPIN (-5525 875) SIG_NAME M_K_CLK_DP<1>
J 0
(-5515 885);
DISPLAY 0.659574 (-5515 885);
PAINT MONO (-5515 885);
DISPLAY INVISIBLE (-5515 885);
FORCEPROP 1 LASTPIN (-5525 875) BN 1
J 0
(-5577 883);
DISPLAY 0.617021 (-5577 883);
PAINT GREEN (-5577 883);
FORCEPROP 2 LAST CDS_LIB mstr_standard
J 0
(-5575 875);
PAINT MONO (-5575 875);
DISPLAY INVISIBLE (-5575 875);
FORCEPROP 1 LAST BODY_TYPE PLUMBING
J 0
(-5575 825);
DISPLAY 1.595745 (-5575 825);
PAINT GREEN (-5575 825);
DISPLAY INVISIBLE (-5575 825);
FORCEPROP 1 LAST HDL_TAP TRUE
J 0
(-5250 750);
DISPLAY 1.595745 (-5250 750);
PAINT GREEN (-5250 750);
DISPLAY INVISIBLE (-5250 750);
FORCEPROP 1 LAST PATH I9
J 0
(-5577 875);
DISPLAY 0.872340 (-5577 875);
PAINT GREEN (-5577 875);
DISPLAY INVISIBLE (-5577 875);
FORCEADD TAP..6
R 2
(-2850 875);
FORCEPROP 3 LASTPIN (-2900 875) SIG_NAME M_K_BG<1>
J 0
(-2890 885);
DISPLAY 0.659574 (-2890 885);
PAINT MONO (-2890 885);
DISPLAY INVISIBLE (-2890 885);
FORCEPROP 1 LASTPIN (-2900 875) BN 1
J 2
(-2848 883);
DISPLAY 0.617021 (-2848 883);
PAINT GREEN (-2848 883);
FORCEPROP 2 LAST CDS_LIB mstr_standard
J 0
(-2850 875);
PAINT MONO (-2850 875);
DISPLAY INVISIBLE (-2850 875);
FORCEPROP 1 LAST BODY_TYPE PLUMBING
J 2
(-2850 825);
DISPLAY 1.595745 (-2850 825);
PAINT GREEN (-2850 825);
DISPLAY INVISIBLE (-2850 825);
FORCEPROP 1 LAST HDL_TAP TRUE
J 2
(-3175 750);
DISPLAY 1.595745 (-3175 750);
PAINT GREEN (-3175 750);
DISPLAY INVISIBLE (-3175 750);
FORCEPROP 1 LAST PATH I90
J 2
(-2848 875);
DISPLAY 0.872340 (-2848 875);
PAINT GREEN (-2848 875);
DISPLAY INVISIBLE (-2848 875);
FORCEADD TAP..6
R 2
(-2850 1075);
FORCEPROP 3 LASTPIN (-2900 1075) SIG_NAME M_K_CS_N<2>
J 0
(-2890 1085);
DISPLAY 0.659574 (-2890 1085);
PAINT MONO (-2890 1085);
DISPLAY INVISIBLE (-2890 1085);
FORCEPROP 1 LASTPIN (-2900 1075) BN 2
J 2
(-2848 1083);
DISPLAY 0.617021 (-2848 1083);
PAINT GREEN (-2848 1083);
FORCEPROP 2 LAST CDS_LIB mstr_standard
J 0
(-2850 1075);
PAINT MONO (-2850 1075);
DISPLAY INVISIBLE (-2850 1075);
FORCEPROP 1 LAST BODY_TYPE PLUMBING
J 2
(-2850 1025);
DISPLAY 1.595745 (-2850 1025);
PAINT GREEN (-2850 1025);
DISPLAY INVISIBLE (-2850 1025);
FORCEPROP 1 LAST HDL_TAP TRUE
J 2
(-3175 950);
DISPLAY 1.595745 (-3175 950);
PAINT GREEN (-3175 950);
DISPLAY INVISIBLE (-3175 950);
FORCEPROP 1 LAST PATH I91
J 2
(-2848 1075);
DISPLAY 0.872340 (-2848 1075);
PAINT GREEN (-2848 1075);
DISPLAY INVISIBLE (-2848 1075);
FORCEADD TAP..6
R 2
(-2850 1025);
FORCEPROP 3 LASTPIN (-2900 1025) SIG_NAME M_K_CS_N<1>
J 0
(-2890 1035);
DISPLAY 0.659574 (-2890 1035);
PAINT MONO (-2890 1035);
DISPLAY INVISIBLE (-2890 1035);
FORCEPROP 1 LASTPIN (-2900 1025) BN 1
J 2
(-2848 1033);
DISPLAY 0.617021 (-2848 1033);
PAINT GREEN (-2848 1033);
FORCEPROP 2 LAST CDS_LIB mstr_standard
J 0
(-2850 1025);
PAINT MONO (-2850 1025);
DISPLAY INVISIBLE (-2850 1025);
FORCEPROP 1 LAST BODY_TYPE PLUMBING
J 2
(-2850 975);
DISPLAY 1.595745 (-2850 975);
PAINT GREEN (-2850 975);
DISPLAY INVISIBLE (-2850 975);
FORCEPROP 1 LAST HDL_TAP TRUE
J 2
(-3175 900);
DISPLAY 1.595745 (-3175 900);
PAINT GREEN (-3175 900);
DISPLAY INVISIBLE (-3175 900);
FORCEPROP 1 LAST PATH I92
J 2
(-2848 1025);
DISPLAY 0.872340 (-2848 1025);
PAINT GREEN (-2848 1025);
DISPLAY INVISIBLE (-2848 1025);
FORCEADD TAP..6
R 2
(-2850 975);
FORCEPROP 3 LASTPIN (-2900 975) SIG_NAME M_K_CS_N<0>
J 0
(-2890 985);
DISPLAY 0.659574 (-2890 985);
PAINT MONO (-2890 985);
DISPLAY INVISIBLE (-2890 985);
FORCEPROP 1 LASTPIN (-2900 975) BN 0
J 2
(-2848 983);
DISPLAY 0.617021 (-2848 983);
PAINT GREEN (-2848 983);
FORCEPROP 2 LAST CDS_LIB mstr_standard
J 0
(-2850 975);
PAINT MONO (-2850 975);
DISPLAY INVISIBLE (-2850 975);
FORCEPROP 1 LAST BODY_TYPE PLUMBING
J 2
(-2850 925);
DISPLAY 1.595745 (-2850 925);
PAINT GREEN (-2850 925);
DISPLAY INVISIBLE (-2850 925);
FORCEPROP 1 LAST HDL_TAP TRUE
J 2
(-3175 850);
DISPLAY 1.595745 (-3175 850);
PAINT GREEN (-3175 850);
DISPLAY INVISIBLE (-3175 850);
FORCEPROP 1 LAST PATH I93
J 2
(-2848 975);
DISPLAY 0.872340 (-2848 975);
PAINT GREEN (-2848 975);
DISPLAY INVISIBLE (-2848 975);
FORCEADD TAP..6
R 2
(-2850 1175);
FORCEPROP 3 LASTPIN (-2900 1175) SIG_NAME M_K_CS_N<4>
J 0
(-2890 1185);
DISPLAY 0.659574 (-2890 1185);
PAINT MONO (-2890 1185);
DISPLAY INVISIBLE (-2890 1185);
FORCEPROP 1 LASTPIN (-2900 1175) BN 4
J 2
(-2848 1183);
DISPLAY 0.617021 (-2848 1183);
PAINT GREEN (-2848 1183);
FORCEPROP 2 LAST CDS_LIB mstr_standard
J 0
(-2850 1175);
PAINT MONO (-2850 1175);
DISPLAY INVISIBLE (-2850 1175);
FORCEPROP 1 LAST BODY_TYPE PLUMBING
J 2
(-2850 1125);
DISPLAY 1.595745 (-2850 1125);
PAINT GREEN (-2850 1125);
DISPLAY INVISIBLE (-2850 1125);
FORCEPROP 1 LAST HDL_TAP TRUE
J 2
(-3175 1050);
DISPLAY 1.595745 (-3175 1050);
PAINT GREEN (-3175 1050);
DISPLAY INVISIBLE (-3175 1050);
FORCEPROP 1 LAST PATH I94
J 2
(-2848 1175);
DISPLAY 0.872340 (-2848 1175);
PAINT GREEN (-2848 1175);
DISPLAY INVISIBLE (-2848 1175);
FORCEADD TAP..6
R 2
(-2850 1125);
FORCEPROP 3 LASTPIN (-2900 1125) SIG_NAME M_K_CS_N<3>
J 0
(-2890 1135);
DISPLAY 0.659574 (-2890 1135);
PAINT MONO (-2890 1135);
DISPLAY INVISIBLE (-2890 1135);
FORCEPROP 1 LASTPIN (-2900 1125) BN 3
J 2
(-2848 1133);
DISPLAY 0.617021 (-2848 1133);
PAINT GREEN (-2848 1133);
FORCEPROP 2 LAST CDS_LIB mstr_standard
J 0
(-2850 1125);
PAINT MONO (-2850 1125);
DISPLAY INVISIBLE (-2850 1125);
FORCEPROP 1 LAST BODY_TYPE PLUMBING
J 2
(-2850 1075);
DISPLAY 1.595745 (-2850 1075);
PAINT GREEN (-2850 1075);
DISPLAY INVISIBLE (-2850 1075);
FORCEPROP 1 LAST HDL_TAP TRUE
J 2
(-3175 1000);
DISPLAY 1.595745 (-3175 1000);
PAINT GREEN (-3175 1000);
DISPLAY INVISIBLE (-3175 1000);
FORCEPROP 1 LAST PATH I95
J 2
(-2848 1125);
DISPLAY 0.872340 (-2848 1125);
PAINT GREEN (-2848 1125);
DISPLAY INVISIBLE (-2848 1125);
FORCEADD TAP..6
R 2
(-2850 1225);
FORCEPROP 3 LASTPIN (-2900 1225) SIG_NAME M_K_CS_N<5>
J 0
(-2890 1235);
DISPLAY 0.659574 (-2890 1235);
PAINT MONO (-2890 1235);
DISPLAY INVISIBLE (-2890 1235);
FORCEPROP 1 LASTPIN (-2900 1225) BN 5
J 2
(-2848 1233);
DISPLAY 0.617021 (-2848 1233);
PAINT GREEN (-2848 1233);
FORCEPROP 2 LAST CDS_LIB mstr_standard
J 0
(-2850 1225);
PAINT MONO (-2850 1225);
DISPLAY INVISIBLE (-2850 1225);
FORCEPROP 1 LAST BODY_TYPE PLUMBING
J 2
(-2850 1175);
DISPLAY 1.595745 (-2850 1175);
PAINT GREEN (-2850 1175);
DISPLAY INVISIBLE (-2850 1175);
FORCEPROP 1 LAST HDL_TAP TRUE
J 2
(-3175 1100);
DISPLAY 1.595745 (-3175 1100);
PAINT GREEN (-3175 1100);
DISPLAY INVISIBLE (-3175 1100);
FORCEPROP 1 LAST PATH I96
J 2
(-2848 1225);
DISPLAY 0.872340 (-2848 1225);
PAINT GREEN (-2848 1225);
DISPLAY INVISIBLE (-2848 1225);
FORCEADD TAP..6
R 2
(-2850 1275);
FORCEPROP 3 LASTPIN (-2900 1275) SIG_NAME M_K_CS_N<6>
J 0
(-2890 1285);
DISPLAY 0.659574 (-2890 1285);
PAINT MONO (-2890 1285);
DISPLAY INVISIBLE (-2890 1285);
FORCEPROP 1 LASTPIN (-2900 1275) BN 6
J 2
(-2848 1283);
DISPLAY 0.617021 (-2848 1283);
PAINT GREEN (-2848 1283);
FORCEPROP 2 LAST CDS_LIB mstr_standard
J 0
(-2850 1275);
PAINT MONO (-2850 1275);
DISPLAY INVISIBLE (-2850 1275);
FORCEPROP 1 LAST BODY_TYPE PLUMBING
J 2
(-2850 1225);
DISPLAY 1.595745 (-2850 1225);
PAINT GREEN (-2850 1225);
DISPLAY INVISIBLE (-2850 1225);
FORCEPROP 1 LAST HDL_TAP TRUE
J 2
(-3175 1150);
DISPLAY 1.595745 (-3175 1150);
PAINT GREEN (-3175 1150);
DISPLAY INVISIBLE (-3175 1150);
FORCEPROP 1 LAST PATH I97
J 2
(-2848 1275);
DISPLAY 0.872340 (-2848 1275);
PAINT GREEN (-2848 1275);
DISPLAY INVISIBLE (-2848 1275);
FORCEADD TAP..6
R 2
(-2850 1325);
FORCEPROP 3 LASTPIN (-2900 1325) SIG_NAME M_K_CS_N<7>
J 0
(-2890 1335);
DISPLAY 0.659574 (-2890 1335);
PAINT MONO (-2890 1335);
DISPLAY INVISIBLE (-2890 1335);
FORCEPROP 1 LASTPIN (-2900 1325) BN 7
J 2
(-2848 1333);
DISPLAY 0.617021 (-2848 1333);
PAINT GREEN (-2848 1333);
FORCEPROP 2 LAST CDS_LIB mstr_standard
J 0
(-2850 1325);
PAINT MONO (-2850 1325);
DISPLAY INVISIBLE (-2850 1325);
FORCEPROP 1 LAST BODY_TYPE PLUMBING
J 2
(-2850 1275);
DISPLAY 1.595745 (-2850 1275);
PAINT GREEN (-2850 1275);
DISPLAY INVISIBLE (-2850 1275);
FORCEPROP 1 LAST HDL_TAP TRUE
J 2
(-3175 1200);
DISPLAY 1.595745 (-3175 1200);
PAINT GREEN (-3175 1200);
DISPLAY INVISIBLE (-3175 1200);
FORCEPROP 1 LAST PATH I98
J 2
(-2848 1325);
DISPLAY 0.872340 (-2848 1325);
PAINT GREEN (-2848 1325);
DISPLAY INVISIBLE (-2848 1325);
FORCEADD TAP..6
R 2
(-2850 1425);
FORCEPROP 3 LASTPIN (-2900 1425) SIG_NAME M_K_ODT<0>
J 0
(-2890 1435);
DISPLAY 0.659574 (-2890 1435);
PAINT MONO (-2890 1435);
DISPLAY INVISIBLE (-2890 1435);
FORCEPROP 1 LASTPIN (-2900 1425) BN 0
J 2
(-2848 1433);
DISPLAY 0.617021 (-2848 1433);
PAINT GREEN (-2848 1433);
FORCEPROP 2 LAST CDS_LIB mstr_standard
J 0
(-2850 1425);
PAINT MONO (-2850 1425);
DISPLAY INVISIBLE (-2850 1425);
FORCEPROP 1 LAST BODY_TYPE PLUMBING
J 2
(-2850 1375);
DISPLAY 1.595745 (-2850 1375);
PAINT GREEN (-2850 1375);
DISPLAY INVISIBLE (-2850 1375);
FORCEPROP 1 LAST HDL_TAP TRUE
J 2
(-3175 1300);
DISPLAY 1.595745 (-3175 1300);
PAINT GREEN (-3175 1300);
DISPLAY INVISIBLE (-3175 1300);
FORCEPROP 1 LAST PATH I99
J 2
(-2848 1425);
DISPLAY 0.872340 (-2848 1425);
PAINT GREEN (-2848 1425);
DISPLAY INVISIBLE (-2848 1425);
FORCEADD DESIGN_NOTE..1
(-6325 375);
FORCEPROP 0 LAST L1 CPU SYMBOLS 1-30 ARE PRELIMINARY AND SUBJECT TO CHANGE
J 0
(-6525 250);
DISPLAY 1.021277 (-6525 250);
PAINT ORANGE (-6525 250);
FORCEPROP 2 LAST CDS_LIB mstr_symbols
J 0
(-6325 375);
PAINT ORANGE (-6325 375);
DISPLAY INVISIBLE (-6325 375);
FORCEPROP 1 LAST COMMENT_BODY TRUE
J 0
(-6300 475);
DISPLAY 0.978723 (-6300 475);
PAINT ORANGE (-6300 475);
DISPLAY INVISIBLE (-6300 475);
FORCEADD PRELIM..10
(-4215 2565);
PAINT GRAY (-4215 2565);
FORCEPROP 2 LAST CDS_LIB mstr_misc
J 0
(-4215 2565);
PAINT ORANGE (-4215 2565);
DISPLAY INVISIBLE (-4215 2565);
FORCEPROP 1 LAST COMMENT_BODY TRUE
J 0
(-4215 2565);
PAINT ORANGE (-4215 2565);
DISPLAY INVISIBLE (-4215 2565);
FORCEADD INTEL_CORP_BPAGE..1
(0 0);
FORCEPROP 1 LAST CDS_CON_LAST_MODIFIED Fri Jun 16 17:48:23 2017
J 0
(-1425 325);
DISPLAY 1.340426 (-1425 325);
PAINT GREEN (-1425 325);
DISPLAY INVISIBLE (-1425 325);
FORCEPROP 1 LAST CUSTOM_TXT_CDS <CURRENT_DESIGN_SHEET> OF <TOTAL_DESIGN_SHEETS>
J 0
(-500 25);
PAINT ORANGE (-500 25);
FORCEPROP 1 LAST CUSTOM_TXT_CDS <CON_LAST_MODIFIED>
J 0
(-4000 100);
PAINT ORANGE (-4000 100);
FORCEPROP 2 LAST CUSTOM_TXT_CDS <XR_PAGE_TITLE>
J 0
(-7890 5250);
DISPLAY 0.638298 (-7890 5250);
PAINT PINK (-7890 5250);
DISPLAY INVISIBLE (-7890 5250);
FORCEPROP 1 LAST SCH_TITLE SKYLAKE - SKT1 - 6 OF 21
J 0
(-7950 50);
DISPLAY 1.212766 (-7950 50);
PAINT GREEN (-7950 50);
FORCEPROP 2 LAST PAGE_BORDER TRUE
J 0
(-7890 5250);
DISPLAY 0.851064 (-7890 5250);
PAINT PINK (-7890 5250);
DISPLAY INVISIBLE (-7890 5250);
FORCEPROP 2 LAST CDS_LIB mstr_symbols
J 0
(0 0);
PAINT ORANGE (0 0);
DISPLAY INVISIBLE (0 0);
FORCEPROP 1 LAST COMMENT_BODY TRUE
J 0
(12 12);
DISPLAY 0.638298 (12 12);
PAINT GREEN (12 12);
DISPLAY INVISIBLE (12 12);
FORCEPROP 2 LAST CDS_XR_PAGE_TITLE CR-60 : @BASEBOARD_FAB2_LIB.BASEBOARD_FAB2(SCH_1):PAGE60
J 0
(-7890 5250);
DISPLAY 0.638298 (-7890 5250);
PAINT PINK (-7890 5250);
DISPLAY INVISIBLE (-7890 5250);
WIRE 17 -1 (-2800 3850)(-2800 3900);
WIRE 17 -1 (-2800 3900)(-2800 3950);
WIRE 17 -1 (-2800 3950)(-2800 4000);
WIRE 17 -1 (-2800 4000)(-2800 4050);
WIRE 17 -1 (-2800 4050)(-2800 4100);
WIRE 17 -1 (-2800 4100)(-2800 4150);
WIRE 17 -1 (-2800 4150)(-2800 4200);
WIRE 17 -1 (-2800 4200)(-2800 4250);
WIRE 17 -1 (-2800 4250)(-2800 4300);
WIRE 17 -1 (-2800 4300)(-2800 4350);
WIRE 17 -1 (-2800 4350)(-2800 4400);
WIRE 17 -1 (-2800 4400)(-2800 4450);
WIRE 17 -1 (-2800 4450)(-2800 4500);
WIRE 17 -1 (-2800 4500)(-2800 4550);
WIRE 17 -1 (-2800 4550)(-2800 4600);
WIRE 17 -1 (-2800 4600)(-2800 4650);
WIRE 17 -1 (-2050 4750)(-2800 4750);
FORCEPROP 2 LAST SIG_NAME M_K_DQS_DP<17:0>
J 0
(-2700 4760);
DISPLAY 0.617021 (-2700 4760);
PAINT ORANGE (-2700 4760);
WIRE 17 -1 (-2800 4650)(-2800 4700);
WIRE 17 -1 (-2800 4700)(-2800 4750);
WIRE 17 -1 (-2800 2900)(-2800 2950);
WIRE 17 -1 (-2800 2950)(-2800 3000);
WIRE 17 -1 (-2800 3000)(-2800 3050);
WIRE 17 -1 (-2800 3050)(-2800 3100);
WIRE 17 -1 (-2800 3100)(-2800 3150);
WIRE 17 -1 (-2800 3150)(-2800 3200);
WIRE 17 -1 (-2800 3200)(-2800 3250);
WIRE 17 -1 (-2800 3250)(-2800 3300);
WIRE 17 -1 (-2800 3300)(-2800 3350);
WIRE 17 -1 (-2800 3350)(-2800 3400);
WIRE 17 -1 (-2800 3400)(-2800 3450);
WIRE 17 -1 (-2800 3450)(-2800 3500);
WIRE 17 -1 (-2800 3500)(-2800 3550);
WIRE 17 -1 (-2800 3550)(-2800 3600);
WIRE 17 -1 (-2800 3600)(-2800 3650);
WIRE 17 -1 (-2800 3650)(-2800 3700);
WIRE 17 -1 (-2050 3775)(-2800 3775);
FORCEPROP 2 LAST SIG_NAME M_K_DQS_DN<17:0>
J 0
(-2700 3785);
DISPLAY 0.617021 (-2700 3785);
PAINT ORANGE (-2700 3785);
WIRE 17 -1 (-2800 3700)(-2800 3750);
WIRE 17 -1 (-2800 3750)(-2800 3775);
WIRE 17 -1 (-2800 1950)(-2800 2000);
WIRE 17 -1 (-2800 2000)(-2800 2050);
WIRE 17 -1 (-2800 2050)(-2800 2100);
WIRE 17 -1 (-2800 2100)(-2800 2150);
WIRE 17 -1 (-2800 2150)(-2800 2200);
WIRE 17 -1 (-2800 2200)(-2800 2250);
WIRE 17 -1 (-2800 2250)(-2800 2300);
WIRE 17 -1 (-2800 2300)(-2800 2350);
WIRE 17 -1 (-2800 2350)(-2800 2400);
WIRE 17 -1 (-2800 2400)(-2800 2450);
WIRE 17 -1 (-2800 2450)(-2800 2500);
WIRE 17 -1 (-2800 2500)(-2800 2550);
WIRE 17 -1 (-2800 2550)(-2800 2600);
WIRE 17 -1 (-2800 2600)(-2800 2650);
WIRE 17 -1 (-2800 2650)(-2800 2700);
WIRE 17 -1 (-2800 2700)(-2800 2750);
WIRE 17 -1 (-2050 2825)(-2800 2825);
FORCEPROP 2 LAST SIG_NAME M_K_MA<17:0>
J 0
(-2700 2835);
DISPLAY 0.617021 (-2700 2835);
PAINT ORANGE (-2700 2835);
WIRE 17 -1 (-2800 2750)(-2800 2800);
WIRE 17 -1 (-2800 2800)(-2800 2825);
WIRE 17 -1 (-2050 825)(-2800 825);
FORCEPROP 2 LAST SIG_NAME M_K_BA<1:0>
J 0
(-2700 835);
DISPLAY 0.617021 (-2700 835);
PAINT ORANGE (-2700 835);
WIRE 17 -1 (-2800 750)(-2800 800);
WIRE 17 -1 (-2800 800)(-2800 825);
WIRE 17 -1 (-2050 925)(-2800 925);
FORCEPROP 2 LAST SIG_NAME M_K_BG<1:0>
J 0
(-2700 935);
DISPLAY 0.617021 (-2700 935);
PAINT ORANGE (-2700 935);
WIRE 17 -1 (-2800 900)(-2800 925);
WIRE 17 -1 (-2800 850)(-2800 900);
WIRE 17 -1 (-2800 1700)(-2800 1750);
WIRE 17 -1 (-2800 1750)(-2800 1800);
WIRE 17 -1 (-2050 1875)(-2800 1875);
FORCEPROP 2 LAST SIG_NAME M_K_CKE<3:0>
J 0
(-2700 1885);
DISPLAY 0.617021 (-2700 1885);
PAINT ORANGE (-2700 1885);
WIRE 17 -1 (-2800 1800)(-2800 1850);
WIRE 17 -1 (-2800 1850)(-2800 1875);
WIRE 17 -1 (-2800 1000)(-2800 1050);
WIRE 17 -1 (-2800 1050)(-2800 1100);
WIRE 17 -1 (-2800 1100)(-2800 1150);
WIRE 17 -1 (-2800 1150)(-2800 1200);
WIRE 17 -1 (-2800 1200)(-2800 1250);
WIRE 17 -1 (-2800 1250)(-2800 1300);
WIRE 17 -1 (-2050 1375)(-2800 1375);
FORCEPROP 2 LAST SIG_NAME M_K_CS_N<7:0>
J 0
(-2700 1385);
DISPLAY 0.617021 (-2700 1385);
PAINT ORANGE (-2700 1385);
WIRE 17 -1 (-2800 1300)(-2800 1350);
WIRE 17 -1 (-2800 1350)(-2800 1375);
WIRE 17 -1 (-2800 1450)(-2800 1500);
WIRE 17 -1 (-2800 1500)(-2800 1550);
WIRE 17 -1 (-2050 1625)(-2800 1625);
FORCEPROP 2 LAST SIG_NAME M_K_ODT<3:0>
J 0
(-2700 1635);
DISPLAY 0.617021 (-2700 1635);
PAINT ORANGE (-2700 1635);
WIRE 17 -1 (-2800 1550)(-2800 1600);
WIRE 17 -1 (-2800 1600)(-2800 1625);
WIRE 17 -1 (-5625 1550)(-5625 1600);
WIRE 17 -1 (-5625 1600)(-5625 1650);
WIRE 17 -1 (-5625 1650)(-5625 1700);
WIRE 17 -1 (-5625 1700)(-5625 1750);
WIRE 17 -1 (-5625 1750)(-5625 1800);
WIRE 17 -1 (-5625 1800)(-5625 1850);
WIRE 17 -1 (-5625 1850)(-5625 1900);
WIRE 17 -1 (-5625 1900)(-5625 1950);
WIRE 17 -1 (-5625 1950)(-5625 2000);
WIRE 17 -1 (-5625 2000)(-5625 2050);
WIRE 17 -1 (-5625 2050)(-5625 2100);
WIRE 17 -1 (-5625 2100)(-5625 2150);
WIRE 17 -1 (-5625 2150)(-5625 2200);
WIRE 17 -1 (-5625 2200)(-5625 2250);
WIRE 17 -1 (-5625 2250)(-5625 2300);
WIRE 17 -1 (-5625 2300)(-5625 2350);
WIRE 17 -1 (-5625 2350)(-5625 2400);
WIRE 17 -1 (-5625 2400)(-5625 2450);
WIRE 17 -1 (-5625 2450)(-5625 2500);
WIRE 17 -1 (-5625 2500)(-5625 2550);
WIRE 17 -1 (-5625 2550)(-5625 2600);
WIRE 17 -1 (-5625 2600)(-5625 2650);
WIRE 17 -1 (-5625 2650)(-5625 2700);
WIRE 17 -1 (-5625 2700)(-5625 2750);
WIRE 17 -1 (-5625 2750)(-5625 2800);
WIRE 17 -1 (-5625 2800)(-5625 2850);
WIRE 17 -1 (-5625 2850)(-5625 2900);
WIRE 17 -1 (-5625 2900)(-5625 2950);
WIRE 17 -1 (-5625 2950)(-5625 3000);
WIRE 17 -1 (-5625 3000)(-5625 3050);
WIRE 17 -1 (-5625 3050)(-5625 3100);
WIRE 17 -1 (-5625 3100)(-5625 3150);
WIRE 17 -1 (-5625 3150)(-5625 3200);
WIRE 17 -1 (-5625 3200)(-5625 3250);
WIRE 17 -1 (-5625 3250)(-5625 3300);
WIRE 17 -1 (-5625 3300)(-5625 3350);
WIRE 17 -1 (-5625 3350)(-5625 3400);
WIRE 17 -1 (-5625 3400)(-5625 3450);
WIRE 17 -1 (-5625 3450)(-5625 3500);
WIRE 17 -1 (-5625 3500)(-5625 3550);
WIRE 17 -1 (-5625 3550)(-5625 3600);
WIRE 17 -1 (-5625 3600)(-5625 3650);
WIRE 17 -1 (-5625 3650)(-5625 3700);
WIRE 17 -1 (-5625 3700)(-5625 3750);
WIRE 17 -1 (-5625 3750)(-5625 3800);
WIRE 17 -1 (-5625 3800)(-5625 3850);
WIRE 17 -1 (-5625 3850)(-5625 3900);
WIRE 17 -1 (-5625 3900)(-5625 3950);
WIRE 17 -1 (-5625 3950)(-5625 4000);
WIRE 17 -1 (-5625 4000)(-5625 4050);
WIRE 17 -1 (-5625 4050)(-5625 4100);
WIRE 17 -1 (-5625 4100)(-5625 4150);
WIRE 17 -1 (-5625 4150)(-5625 4200);
WIRE 17 -1 (-5625 4200)(-5625 4250);
WIRE 17 -1 (-5625 4250)(-5625 4300);
WIRE 17 -1 (-5625 4300)(-5625 4350);
WIRE 17 -1 (-5625 4350)(-5625 4400);
WIRE 17 -1 (-5625 4400)(-5625 4450);
WIRE 17 -1 (-5625 4450)(-5625 4500);
WIRE 17 -1 (-5625 4500)(-5625 4550);
WIRE 17 -1 (-5625 4550)(-5625 4600);
WIRE 17 -1 (-5625 4600)(-5625 4650);
WIRE 17 -1 (-5625 4800)(-6375 4800);
FORCEPROP 2 LAST SIG_NAME M_K_DQ<63:0>
J 0
(-6325 4810);
DISPLAY 0.617021 (-6325 4810);
PAINT ORANGE (-6325 4810);
WIRE 17 -1 (-5625 4650)(-5625 4700);
WIRE 17 -1 (-5625 4700)(-5625 4800);
WIRE 17 -1 (-5625 650)(-5625 700);
WIRE 17 -1 (-5625 700)(-5625 750);
WIRE 17 -1 (-5625 825)(-6375 825);
FORCEPROP 2 LAST SIG_NAME M_K_CLK_DN<3:0>
J 0
(-6325 835);
DISPLAY 0.617021 (-6325 835);
PAINT ORANGE (-6325 835);
WIRE 17 -1 (-5625 750)(-5625 800);
WIRE 17 -1 (-5625 800)(-5625 825);
WIRE 17 -1 (-5625 850)(-5625 900);
WIRE 17 -1 (-5625 900)(-5625 950);
WIRE 17 -1 (-5625 1025)(-6375 1025);
FORCEPROP 2 LAST SIG_NAME M_K_CLK_DP<3:0>
J 0
(-6325 1035);
DISPLAY 0.617021 (-6325 1035);
PAINT ORANGE (-6325 1035);
WIRE 17 -1 (-5625 950)(-5625 1000);
WIRE 17 -1 (-5625 1000)(-5625 1025);
WIRE 17 -1 (-5625 1100)(-5625 1150);
WIRE 17 -1 (-5625 1150)(-5625 1200);
WIRE 17 -1 (-5625 1200)(-5625 1250);
WIRE 17 -1 (-5625 1250)(-5625 1300);
WIRE 17 -1 (-5625 1300)(-5625 1350);
WIRE 17 -1 (-5625 1350)(-5625 1400);
WIRE 17 -1 (-5625 1475)(-6375 1475);
FORCEPROP 2 LAST SIG_NAME M_K_ECC<7:0>
J 0
(-6325 1485);
DISPLAY 0.617021 (-6325 1485);
PAINT ORANGE (-6325 1485);
WIRE 17 -1 (-5625 1400)(-5625 1450);
WIRE 17 -1 (-5625 1450)(-5625 1475);
WIRE 16 -1 (-5025 4275)(-5525 4275);
WIRE 16 -1 (-5025 1125)(-5525 1125);
WIRE 16 -1 (-5525 3575)(-5025 3575);
WIRE 16 -1 (-5025 4125)(-5525 4125);
WIRE 16 -1 (-3325 1525)(-2900 1525);
WIRE 16 -1 (-5525 3225)(-5025 3225);
WIRE 16 -1 (-5525 3125)(-5025 3125);
WIRE 16 -1 (-5025 525)(-6375 525);
FORCEPROP 2 LAST SIG_NAME M_K_C<2>
J 0
(-6325 535);
DISPLAY 0.617021 (-6325 535);
PAINT ORANGE (-6325 535);
WIRE 16 -1 (-5025 1075)(-5525 1075);
WIRE 16 -1 (-5025 1175)(-5525 1175);
WIRE 16 -1 (-5025 1225)(-5525 1225);
WIRE 16 -1 (-5025 1275)(-5525 1275);
WIRE 16 -1 (-5025 1325)(-5525 1325);
WIRE 16 -1 (-5025 1375)(-5525 1375);
WIRE 16 -1 (-5025 1425)(-5525 1425);
WIRE 16 -1 (-5525 1525)(-5025 1525);
WIRE 16 -1 (-5525 1575)(-5025 1575);
WIRE 16 -1 (-5525 1625)(-5025 1625);
WIRE 16 -1 (-5025 1675)(-5525 1675);
WIRE 16 -1 (-5525 1725)(-5025 1725);
WIRE 16 -1 (-5525 1775)(-5025 1775);
WIRE 16 -1 (-5025 1825)(-5525 1825);
WIRE 16 -1 (-5525 1875)(-5025 1875);
WIRE 16 -1 (-5525 1925)(-5025 1925);
WIRE 16 -1 (-5525 1975)(-5025 1975);
WIRE 16 -1 (-5525 2025)(-5025 2025);
WIRE 16 -1 (-5025 825)(-5525 825);
WIRE 16 -1 (-5025 875)(-5525 875);
WIRE 16 -1 (-5025 925)(-5525 925);
WIRE 16 -1 (-5025 975)(-5525 975);
WIRE 16 -1 (-5025 625)(-5525 625);
WIRE 16 -1 (-5025 675)(-5525 675);
WIRE 16 -1 (-5025 725)(-5525 725);
WIRE 16 -1 (-5025 775)(-5525 775);
WIRE 16 -1 (-5525 2075)(-5025 2075);
WIRE 16 -1 (-5525 2125)(-5025 2125);
WIRE 16 -1 (-5525 2175)(-5025 2175);
WIRE 16 -1 (-5525 2225)(-5025 2225);
WIRE 16 -1 (-5025 2275)(-5525 2275);
WIRE 16 -1 (-5525 2325)(-5025 2325);
WIRE 16 -1 (-5525 2375)(-5025 2375);
WIRE 16 -1 (-5025 2425)(-5525 2425);
WIRE 16 -1 (-5525 2475)(-5025 2475);
WIRE 16 -1 (-5525 2525)(-5025 2525);
WIRE 16 -1 (-5525 2575)(-5025 2575);
WIRE 16 -1 (-5525 2625)(-5025 2625);
WIRE 16 -1 (-5025 2675)(-5525 2675);
WIRE 16 -1 (-5525 2725)(-5025 2725);
WIRE 16 -1 (-5525 2775)(-5025 2775);
WIRE 16 -1 (-5525 2825)(-5025 2825);
WIRE 16 -1 (-5525 2875)(-5025 2875);
WIRE 16 -1 (-5525 2925)(-5025 2925);
WIRE 16 -1 (-5525 2975)(-5025 2975);
WIRE 16 -1 (-5025 3025)(-5525 3025);
WIRE 16 -1 (-5525 3075)(-5025 3075);
WIRE 16 -1 (-5525 3175)(-5025 3175);
WIRE 16 -1 (-5525 3275)(-5025 3275);
WIRE 16 -1 (-5525 3325)(-5025 3325);
WIRE 16 -1 (-5025 3375)(-5525 3375);
WIRE 16 -1 (-5525 3425)(-5025 3425);
WIRE 16 -1 (-5525 3475)(-5025 3475);
WIRE 16 -1 (-5025 3525)(-5525 3525);
WIRE 16 -1 (-5525 3625)(-5025 3625);
WIRE 16 -1 (-5025 3675)(-5525 3675);
WIRE 16 -1 (-5025 3725)(-5525 3725);
WIRE 16 -1 (-5025 3775)(-5525 3775);
WIRE 16 -1 (-5025 3825)(-5525 3825);
WIRE 16 -1 (-5025 3875)(-5525 3875);
WIRE 16 -1 (-5025 3925)(-5525 3925);
WIRE 16 -1 (-5025 3975)(-5525 3975);
WIRE 16 -1 (-5025 4025)(-5525 4025);
WIRE 16 -1 (-5025 4075)(-5525 4075);
WIRE 16 -1 (-5025 4175)(-5525 4175);
WIRE 16 -1 (-5025 4225)(-5525 4225);
WIRE 16 -1 (-5025 4325)(-5525 4325);
WIRE 16 -1 (-5025 4375)(-5525 4375);
WIRE 16 -1 (-5025 4425)(-5525 4425);
WIRE 16 -1 (-5025 4475)(-5525 4475);
WIRE 16 -1 (-5025 4525)(-5525 4525);
WIRE 16 -1 (-5025 4575)(-5525 4575);
WIRE 16 -1 (-5025 4625)(-5525 4625);
WIRE 16 -1 (-5025 4675)(-5525 4675);
WIRE 16 -1 (-3325 1425)(-2900 1425);
WIRE 16 -1 (-3325 1475)(-2900 1475);
WIRE 16 -1 (-3325 1575)(-2900 1575);
WIRE 16 -1 (-3325 1925)(-2900 1925);
WIRE 16 -1 (-3325 1975)(-2900 1975);
WIRE 16 -1 (-3325 2025)(-2900 2025);
WIRE 16 -1 (-3325 975)(-2900 975);
WIRE 16 -1 (-3325 1025)(-2900 1025);
WIRE 16 -1 (-3325 1075)(-2900 1075);
WIRE 16 -1 (-3325 1125)(-2900 1125);
WIRE 16 -1 (-3325 1175)(-2900 1175);
WIRE 16 -1 (-3325 1225)(-2900 1225);
WIRE 16 -1 (-3325 1275)(-2900 1275);
WIRE 16 -1 (-3325 1325)(-2900 1325);
WIRE 16 -1 (-3325 1675)(-2900 1675);
WIRE 16 -1 (-3325 1725)(-2900 1725);
WIRE 16 -1 (-3325 1775)(-2900 1775);
WIRE 16 -1 (-3325 1825)(-2900 1825);
WIRE 16 -1 (-3325 825)(-2900 825);
WIRE 16 -1 (-3325 875)(-2900 875);
WIRE 16 -1 (-3325 725)(-2900 725);
WIRE 16 -1 (-3325 775)(-2900 775);
WIRE 16 -1 (-3325 525)(-2050 525);
FORCEPROP 2 LAST SIG_NAME M_K_PAR
J 0
(-2700 535);
DISPLAY 0.617021 (-2700 535);
PAINT ORANGE (-2700 535);
WIRE 16 -1 (-3325 575)(-2050 575);
FORCEPROP 2 LAST SIG_NAME M_K_ALERT_N
J 0
(-2700 585);
DISPLAY 0.617021 (-2700 585);
PAINT ORANGE (-2700 585);
WIRE 16 -1 (-3325 625)(-2050 625);
FORCEPROP 2 LAST SIG_NAME M_K_ACT_N
J 0
(-2700 635);
DISPLAY 0.617021 (-2700 635);
PAINT ORANGE (-2700 635);
WIRE 16 -1 (-3325 2075)(-2900 2075);
WIRE 16 -1 (-3325 2125)(-2900 2125);
WIRE 16 -1 (-3325 2175)(-2900 2175);
WIRE 16 -1 (-3325 2225)(-2900 2225);
WIRE 16 -1 (-3325 2275)(-2900 2275);
WIRE 16 -1 (-3325 2325)(-2900 2325);
WIRE 16 -1 (-3325 2375)(-2900 2375);
WIRE 16 -1 (-3325 2425)(-2900 2425);
WIRE 16 -1 (-3325 2475)(-2900 2475);
WIRE 16 -1 (-3325 2525)(-2900 2525);
WIRE 16 -1 (-3325 2575)(-2900 2575);
WIRE 16 -1 (-3325 2625)(-2900 2625);
WIRE 16 -1 (-3325 2675)(-2900 2675);
WIRE 16 -1 (-3325 2725)(-2900 2725);
WIRE 16 -1 (-3325 2775)(-2900 2775);
WIRE 16 -1 (-3325 3825)(-2900 3825);
WIRE 16 -1 (-3325 3875)(-2900 3875);
WIRE 16 -1 (-3325 3925)(-2900 3925);
WIRE 16 -1 (-3325 3975)(-2900 3975);
WIRE 16 -1 (-3325 4025)(-2900 4025);
WIRE 16 -1 (-3325 4075)(-2900 4075);
WIRE 16 -1 (-3325 2875)(-2900 2875);
WIRE 16 -1 (-3325 2925)(-2900 2925);
WIRE 16 -1 (-3325 2975)(-2900 2975);
WIRE 16 -1 (-3325 3025)(-2900 3025);
WIRE 16 -1 (-3325 3075)(-2900 3075);
WIRE 16 -1 (-3325 3125)(-2900 3125);
WIRE 16 -1 (-3325 3175)(-2900 3175);
WIRE 16 -1 (-3325 3225)(-2900 3225);
WIRE 16 -1 (-3325 3275)(-2900 3275);
WIRE 16 -1 (-3325 3325)(-2900 3325);
WIRE 16 -1 (-3325 3375)(-2900 3375);
WIRE 16 -1 (-3325 3425)(-2900 3425);
WIRE 16 -1 (-3325 3475)(-2900 3475);
WIRE 16 -1 (-3325 3525)(-2900 3525);
WIRE 16 -1 (-3325 3575)(-2900 3575);
WIRE 16 -1 (-3325 3625)(-2900 3625);
WIRE 16 -1 (-3325 3675)(-2900 3675);
WIRE 16 -1 (-3325 3725)(-2900 3725);
WIRE 16 -1 (-3325 4125)(-2900 4125);
WIRE 16 -1 (-3325 4175)(-2900 4175);
WIRE 16 -1 (-3325 4225)(-2900 4225);
WIRE 16 -1 (-3325 4275)(-2900 4275);
WIRE 16 -1 (-3325 4325)(-2900 4325);
WIRE 16 -1 (-3325 4375)(-2900 4375);
WIRE 16 -1 (-3325 4425)(-2900 4425);
WIRE 16 -1 (-3325 4475)(-2900 4475);
WIRE 16 -1 (-3325 4525)(-2900 4525);
WIRE 16 -1 (-3325 4575)(-2900 4575);
WIRE 16 -1 (-3325 4625)(-2900 4625);
WIRE 16 -1 (-3325 4675)(-2900 4675);
FORCENOTE
ROOM=CPU1
(-7975 350) 0;
DISPLAY LEFT (-7975 350);
DISPLAY 1.723404 (-7975 350);
PAINT PURPLE (-7975 350);
FORCENOTE
BOM_COST=PROC_SOCKET
(-7975 225) 0;
DISPLAY LEFT (-7975 225);
DISPLAY 1.723404 (-7975 225);
PAINT PURPLE (-7975 225);
QUIT
